FILE_TYPE = MACRO_DRAWING;
SET COLOR_WIRE YELLOW;
SET COLOR_PROP ORANGE;
SET COLOR_DOT WHITE;
SET COLOR_ARC YELLOW;
SET COLOR_BODY GREEN;
SET COLOR_NOTE PURPLE;
SET PROP_DISPLAY VALUE;
SET PAGE_NUMBER P27;
FORCEADD OFFPAGE..2
R 2
(-1975 475);
FORCEPROP 2 LAST $XR1 97 
J 0
(-2319 475);
DISPLAY 0.638298 (-2319 475);
PAINT MONO (-2319 475);
FORCEPROP 2 LAST $XR0 96 
J 0
(-2229 475);
DISPLAY 0.638298 (-2229 475);
PAINT MONO (-2229 475);
FORCEPROP 2 LAST CDS_LIB standard
J 0
(-1975 475);
PAINT MONO (-1975 475);
DISPLAY INVISIBLE (-1975 475);
FORCEPROP 1 LAST OFFPAGE TRUE
J 2
(-2300 350);
DISPLAY 0.872340 (-2300 350);
DISPLAY INVISIBLE (-2300 350);
FORCEPROP 1 LAST COMMENT_BODY TRUE
J 2
(-1930 380);
DISPLAY 0.872340 (-1930 380);
PAINT GREEN (-1930 380);
DISPLAY INVISIBLE (-1930 380);
FORCEPROP 2 LAST PATH I1
J 0
(-1925 550);
DISPLAY 1.021277 (-1925 550);
DISPLAY INVISIBLE (-1925 550);
FORCEADD OFFPAGE..3
R 2
(-1975 925);
FORCEPROP 2 LAST $XR1 97 
J 0
(-2344 925);
DISPLAY 0.638298 (-2344 925);
PAINT MONO (-2344 925);
FORCEPROP 2 LAST $XR0 96 
J 0
(-2254 925);
DISPLAY 0.638298 (-2254 925);
PAINT MONO (-2254 925);
FORCEPROP 2 LAST CDS_LIB standard
J 0
(-1975 925);
DISPLAY INVISIBLE (-1975 925);
FORCEPROP 1 LAST OFFPAGE TRUE
J 2
(-2300 800);
DISPLAY 0.872340 (-2300 800);
DISPLAY INVISIBLE (-2300 800);
FORCEPROP 1 LAST COMMENT_BODY TRUE
J 2
(-1925 825);
DISPLAY 0.872340 (-1925 825);
PAINT GREEN (-1925 825);
DISPLAY INVISIBLE (-1925 825);
FORCEPROP 2 LAST PATH I10
J 0
(-1925 1000);
DISPLAY 1.021277 (-1925 1000);
DISPLAY INVISIBLE (-1925 1000);
FORCEADD TAP..1
(2475 850);
FORCEPROP 3 LASTPIN (2425 850) SIG_NAME M_H_CPU0_SB_CS_N<2>
J 0
(2435 860);
DISPLAY 0.659574 (2435 860);
PAINT MONO (2435 860);
DISPLAY INVISIBLE (2435 860);
FORCEPROP 1 LASTPIN (2425 850) BN 2
J 0
(2413 858);
DISPLAY 0.680851 (2413 858);
PAINT GREEN (2413 858);
FORCEPROP 2 LAST CDS_LIB standard
J 0
(2475 850);
DISPLAY INVISIBLE (2475 850);
FORCEPROP 1 LAST BODY_TYPE PLUMBING
J 0
(2475 900);
DISPLAY 0.872340 (2475 900);
PAINT GREEN (2475 900);
DISPLAY INVISIBLE (2475 900);
FORCEPROP 1 LAST HDL_TAP TRUE
J 0
(2800 725);
DISPLAY 0.872340 (2800 725);
DISPLAY INVISIBLE (2800 725);
FORCEPROP 1 LAST PATH I100
J 0
(2473 850);
DISPLAY 0.872340 (2473 850);
PAINT GREEN (2473 850);
DISPLAY INVISIBLE (2473 850);
FORCEADD TAP..1
(2475 1100);
FORCEPROP 3 LASTPIN (2425 1100) SIG_NAME M_H_CPU0_SA_CS_N<1>
J 0
(2435 1110);
DISPLAY 0.659574 (2435 1110);
PAINT MONO (2435 1110);
DISPLAY INVISIBLE (2435 1110);
FORCEPROP 1 LASTPIN (2425 1100) BN 1
J 0
(2413 1108);
DISPLAY 0.680851 (2413 1108);
PAINT GREEN (2413 1108);
FORCEPROP 2 LAST CDS_LIB standard
J 0
(2475 1100);
DISPLAY INVISIBLE (2475 1100);
FORCEPROP 1 LAST BODY_TYPE PLUMBING
J 0
(2475 1150);
DISPLAY 0.872340 (2475 1150);
PAINT GREEN (2475 1150);
DISPLAY INVISIBLE (2475 1150);
FORCEPROP 1 LAST HDL_TAP TRUE
J 0
(2800 975);
DISPLAY 0.872340 (2800 975);
DISPLAY INVISIBLE (2800 975);
FORCEPROP 1 LAST PATH I101
J 0
(2473 1100);
DISPLAY 0.872340 (2473 1100);
PAINT GREEN (2473 1100);
DISPLAY INVISIBLE (2473 1100);
FORCEADD TAP..1
(2475 1150);
FORCEPROP 3 LASTPIN (2425 1150) SIG_NAME M_H_CPU0_SA_CS_N<2>
J 0
(2435 1160);
DISPLAY 0.659574 (2435 1160);
PAINT MONO (2435 1160);
DISPLAY INVISIBLE (2435 1160);
FORCEPROP 1 LASTPIN (2425 1150) BN 2
J 0
(2413 1158);
DISPLAY 0.680851 (2413 1158);
PAINT GREEN (2413 1158);
FORCEPROP 2 LAST CDS_LIB standard
J 0
(2475 1150);
DISPLAY INVISIBLE (2475 1150);
FORCEPROP 1 LAST BODY_TYPE PLUMBING
J 0
(2475 1200);
DISPLAY 0.872340 (2475 1200);
PAINT GREEN (2475 1200);
DISPLAY INVISIBLE (2475 1200);
FORCEPROP 1 LAST HDL_TAP TRUE
J 0
(2800 1025);
DISPLAY 0.872340 (2800 1025);
DISPLAY INVISIBLE (2800 1025);
FORCEPROP 1 LAST PATH I102
J 0
(2473 1150);
DISPLAY 0.872340 (2473 1150);
PAINT GREEN (2473 1150);
DISPLAY INVISIBLE (2473 1150);
FORCEADD TAP..1
(2475 1050);
FORCEPROP 3 LASTPIN (2425 1050) SIG_NAME M_H_CPU0_SA_CS_N<0>
J 0
(2435 1060);
DISPLAY 0.659574 (2435 1060);
PAINT MONO (2435 1060);
DISPLAY INVISIBLE (2435 1060);
FORCEPROP 1 LASTPIN (2425 1050) BN 0
J 0
(2413 1058);
DISPLAY 0.680851 (2413 1058);
PAINT GREEN (2413 1058);
FORCEPROP 2 LAST CDS_LIB standard
J 0
(2475 1050);
DISPLAY INVISIBLE (2475 1050);
FORCEPROP 1 LAST BODY_TYPE PLUMBING
J 0
(2475 1100);
DISPLAY 0.872340 (2475 1100);
PAINT GREEN (2475 1100);
DISPLAY INVISIBLE (2475 1100);
FORCEPROP 1 LAST HDL_TAP TRUE
J 0
(2800 925);
DISPLAY 0.872340 (2800 925);
DISPLAY INVISIBLE (2800 925);
FORCEPROP 1 LAST PATH I103
J 0
(2473 1050);
DISPLAY 0.872340 (2473 1050);
PAINT GREEN (2473 1050);
DISPLAY INVISIBLE (2473 1050);
FORCEADD TAP..1
(2475 1200);
FORCEPROP 3 LASTPIN (2425 1200) SIG_NAME M_H_CPU0_SA_CS_N<3>
J 0
(2435 1210);
DISPLAY 0.659574 (2435 1210);
PAINT MONO (2435 1210);
DISPLAY INVISIBLE (2435 1210);
FORCEPROP 1 LASTPIN (2425 1200) BN 3
J 0
(2413 1208);
DISPLAY 0.680851 (2413 1208);
PAINT GREEN (2413 1208);
FORCEPROP 2 LAST CDS_LIB standard
J 0
(2475 1200);
DISPLAY INVISIBLE (2475 1200);
FORCEPROP 1 LAST BODY_TYPE PLUMBING
J 0
(2475 1250);
DISPLAY 0.872340 (2475 1250);
PAINT GREEN (2475 1250);
DISPLAY INVISIBLE (2475 1250);
FORCEPROP 1 LAST HDL_TAP TRUE
J 0
(2800 1075);
DISPLAY 0.872340 (2800 1075);
DISPLAY INVISIBLE (2800 1075);
FORCEPROP 1 LAST PATH I104
J 0
(2473 1200);
DISPLAY 0.872340 (2473 1200);
PAINT GREEN (2473 1200);
DISPLAY INVISIBLE (2473 1200);
FORCEADD TAP..1
(2475 1400);
FORCEPROP 3 LASTPIN (2425 1400) SIG_NAME M_H_CPU0_SB_CA<0>
J 0
(2435 1410);
DISPLAY 0.659574 (2435 1410);
PAINT MONO (2435 1410);
DISPLAY INVISIBLE (2435 1410);
FORCEPROP 1 LASTPIN (2425 1400) BN 0
J 0
(2413 1408);
DISPLAY 0.680851 (2413 1408);
PAINT GREEN (2413 1408);
FORCEPROP 2 LAST CDS_LIB standard
J 0
(2475 1400);
DISPLAY INVISIBLE (2475 1400);
FORCEPROP 1 LAST BODY_TYPE PLUMBING
J 0
(2475 1450);
DISPLAY 0.872340 (2475 1450);
PAINT GREEN (2475 1450);
DISPLAY INVISIBLE (2475 1450);
FORCEPROP 1 LAST HDL_TAP TRUE
J 0
(2800 1275);
DISPLAY 0.872340 (2800 1275);
DISPLAY INVISIBLE (2800 1275);
FORCEPROP 1 LAST PATH I105
J 0
(2473 1400);
DISPLAY 0.872340 (2473 1400);
PAINT GREEN (2473 1400);
DISPLAY INVISIBLE (2473 1400);
FORCEADD TAP..1
(2475 1500);
FORCEPROP 3 LASTPIN (2425 1500) SIG_NAME M_H_CPU0_SB_CA<2>
J 0
(2435 1510);
DISPLAY 0.659574 (2435 1510);
PAINT MONO (2435 1510);
DISPLAY INVISIBLE (2435 1510);
FORCEPROP 1 LASTPIN (2425 1500) BN 2
J 0
(2413 1508);
DISPLAY 0.680851 (2413 1508);
PAINT GREEN (2413 1508);
FORCEPROP 2 LAST CDS_LIB standard
J 0
(2475 1500);
DISPLAY INVISIBLE (2475 1500);
FORCEPROP 1 LAST BODY_TYPE PLUMBING
J 0
(2475 1550);
DISPLAY 0.872340 (2475 1550);
PAINT GREEN (2475 1550);
DISPLAY INVISIBLE (2475 1550);
FORCEPROP 1 LAST HDL_TAP TRUE
J 0
(2800 1375);
DISPLAY 0.872340 (2800 1375);
DISPLAY INVISIBLE (2800 1375);
FORCEPROP 1 LAST PATH I106
J 0
(2473 1500);
DISPLAY 0.872340 (2473 1500);
PAINT GREEN (2473 1500);
DISPLAY INVISIBLE (2473 1500);
FORCEADD TAP..1
(2475 1450);
FORCEPROP 3 LASTPIN (2425 1450) SIG_NAME M_H_CPU0_SB_CA<1>
J 0
(2435 1460);
DISPLAY 0.659574 (2435 1460);
PAINT MONO (2435 1460);
DISPLAY INVISIBLE (2435 1460);
FORCEPROP 1 LASTPIN (2425 1450) BN 1
J 0
(2413 1458);
DISPLAY 0.680851 (2413 1458);
PAINT GREEN (2413 1458);
FORCEPROP 2 LAST CDS_LIB standard
J 0
(2475 1450);
DISPLAY INVISIBLE (2475 1450);
FORCEPROP 1 LAST BODY_TYPE PLUMBING
J 0
(2475 1500);
DISPLAY 0.872340 (2475 1500);
PAINT GREEN (2475 1500);
DISPLAY INVISIBLE (2475 1500);
FORCEPROP 1 LAST HDL_TAP TRUE
J 0
(2800 1325);
DISPLAY 0.872340 (2800 1325);
DISPLAY INVISIBLE (2800 1325);
FORCEPROP 1 LAST PATH I107
J 0
(2473 1450);
DISPLAY 0.872340 (2473 1450);
PAINT GREEN (2473 1450);
DISPLAY INVISIBLE (2473 1450);
FORCEADD TAP..1
(2475 1650);
FORCEPROP 3 LASTPIN (2425 1650) SIG_NAME M_H_CPU0_SB_CA<5>
J 0
(2435 1660);
DISPLAY 0.659574 (2435 1660);
PAINT MONO (2435 1660);
DISPLAY INVISIBLE (2435 1660);
FORCEPROP 1 LASTPIN (2425 1650) BN 5
J 0
(2413 1658);
DISPLAY 0.680851 (2413 1658);
PAINT GREEN (2413 1658);
FORCEPROP 2 LAST CDS_LIB standard
J 0
(2475 1650);
DISPLAY INVISIBLE (2475 1650);
FORCEPROP 1 LAST BODY_TYPE PLUMBING
J 0
(2475 1700);
DISPLAY 0.872340 (2475 1700);
PAINT GREEN (2475 1700);
DISPLAY INVISIBLE (2475 1700);
FORCEPROP 1 LAST HDL_TAP TRUE
J 0
(2800 1525);
DISPLAY 0.872340 (2800 1525);
DISPLAY INVISIBLE (2800 1525);
FORCEPROP 1 LAST PATH I108
J 0
(2473 1650);
DISPLAY 0.872340 (2473 1650);
PAINT GREEN (2473 1650);
DISPLAY INVISIBLE (2473 1650);
FORCEADD TAP..1
(2475 1550);
FORCEPROP 3 LASTPIN (2425 1550) SIG_NAME M_H_CPU0_SB_CA<3>
J 0
(2435 1560);
DISPLAY 0.659574 (2435 1560);
PAINT MONO (2435 1560);
DISPLAY INVISIBLE (2435 1560);
FORCEPROP 1 LASTPIN (2425 1550) BN 3
J 0
(2413 1558);
DISPLAY 0.680851 (2413 1558);
PAINT GREEN (2413 1558);
FORCEPROP 2 LAST CDS_LIB standard
J 0
(2475 1550);
DISPLAY INVISIBLE (2475 1550);
FORCEPROP 1 LAST BODY_TYPE PLUMBING
J 0
(2475 1600);
DISPLAY 0.872340 (2475 1600);
PAINT GREEN (2475 1600);
DISPLAY INVISIBLE (2475 1600);
FORCEPROP 1 LAST HDL_TAP TRUE
J 0
(2800 1425);
DISPLAY 0.872340 (2800 1425);
DISPLAY INVISIBLE (2800 1425);
FORCEPROP 1 LAST PATH I109
J 0
(2473 1550);
DISPLAY 0.872340 (2473 1550);
PAINT GREEN (2473 1550);
DISPLAY INVISIBLE (2473 1550);
FORCEADD OFFPAGE..3
R 2
(-1975 2525);
FORCEPROP 2 LAST $XR1 97 
J 0
(-2344 2525);
DISPLAY 0.638298 (-2344 2525);
PAINT MONO (-2344 2525);
FORCEPROP 2 LAST $XR0 96 
J 0
(-2254 2525);
DISPLAY 0.638298 (-2254 2525);
PAINT MONO (-2254 2525);
FORCEPROP 2 LAST CDS_LIB standard
J 0
(-1975 2525);
DISPLAY INVISIBLE (-1975 2525);
FORCEPROP 1 LAST OFFPAGE TRUE
J 2
(-2300 2400);
DISPLAY 0.872340 (-2300 2400);
DISPLAY INVISIBLE (-2300 2400);
FORCEPROP 1 LAST COMMENT_BODY TRUE
J 2
(-1925 2425);
DISPLAY 0.872340 (-1925 2425);
PAINT GREEN (-1925 2425);
DISPLAY INVISIBLE (-1925 2425);
FORCEPROP 2 LAST PATH I11
J 0
(-1925 2600);
DISPLAY 1.021277 (-1925 2600);
DISPLAY INVISIBLE (-1925 2600);
FORCEADD TAP..1
(2475 1600);
FORCEPROP 3 LASTPIN (2425 1600) SIG_NAME M_H_CPU0_SB_CA<4>
J 0
(2435 1610);
DISPLAY 0.659574 (2435 1610);
PAINT MONO (2435 1610);
DISPLAY INVISIBLE (2435 1610);
FORCEPROP 1 LASTPIN (2425 1600) BN 4
J 0
(2413 1608);
DISPLAY 0.680851 (2413 1608);
PAINT GREEN (2413 1608);
FORCEPROP 2 LAST CDS_LIB standard
J 0
(2475 1600);
DISPLAY INVISIBLE (2475 1600);
FORCEPROP 1 LAST BODY_TYPE PLUMBING
J 0
(2475 1650);
DISPLAY 0.872340 (2475 1650);
PAINT GREEN (2475 1650);
DISPLAY INVISIBLE (2475 1650);
FORCEPROP 1 LAST HDL_TAP TRUE
J 0
(2800 1475);
DISPLAY 0.872340 (2800 1475);
DISPLAY INVISIBLE (2800 1475);
FORCEPROP 1 LAST PATH I110
J 0
(2473 1600);
DISPLAY 0.872340 (2473 1600);
PAINT GREEN (2473 1600);
DISPLAY INVISIBLE (2473 1600);
FORCEADD TAP..1
(2475 1700);
FORCEPROP 3 LASTPIN (2425 1700) SIG_NAME M_H_CPU0_SB_CA<6>
J 0
(2435 1710);
DISPLAY 0.659574 (2435 1710);
PAINT MONO (2435 1710);
DISPLAY INVISIBLE (2435 1710);
FORCEPROP 1 LASTPIN (2425 1700) BN 6
J 0
(2413 1708);
DISPLAY 0.680851 (2413 1708);
PAINT GREEN (2413 1708);
FORCEPROP 2 LAST CDS_LIB standard
J 0
(2475 1700);
DISPLAY INVISIBLE (2475 1700);
FORCEPROP 1 LAST BODY_TYPE PLUMBING
J 0
(2475 1750);
DISPLAY 0.872340 (2475 1750);
PAINT GREEN (2475 1750);
DISPLAY INVISIBLE (2475 1750);
FORCEPROP 1 LAST HDL_TAP TRUE
J 0
(2800 1575);
DISPLAY 0.872340 (2800 1575);
DISPLAY INVISIBLE (2800 1575);
FORCEPROP 1 LAST PATH I111
J 0
(2473 1700);
DISPLAY 0.872340 (2473 1700);
PAINT GREEN (2473 1700);
DISPLAY INVISIBLE (2473 1700);
FORCEADD TAP..1
(2475 1900);
FORCEPROP 3 LASTPIN (2425 1900) SIG_NAME M_H_CPU0_SA_CA<0>
J 0
(2435 1910);
DISPLAY 0.659574 (2435 1910);
PAINT MONO (2435 1910);
DISPLAY INVISIBLE (2435 1910);
FORCEPROP 1 LASTPIN (2425 1900) BN 0
J 0
(2413 1908);
DISPLAY 0.680851 (2413 1908);
PAINT GREEN (2413 1908);
FORCEPROP 2 LAST CDS_LIB standard
J 0
(2475 1900);
DISPLAY INVISIBLE (2475 1900);
FORCEPROP 1 LAST BODY_TYPE PLUMBING
J 0
(2475 1950);
DISPLAY 0.872340 (2475 1950);
PAINT GREEN (2475 1950);
DISPLAY INVISIBLE (2475 1950);
FORCEPROP 1 LAST HDL_TAP TRUE
J 0
(2800 1775);
DISPLAY 0.872340 (2800 1775);
DISPLAY INVISIBLE (2800 1775);
FORCEPROP 1 LAST PATH I112
J 0
(2473 1900);
DISPLAY 0.872340 (2473 1900);
PAINT GREEN (2473 1900);
DISPLAY INVISIBLE (2473 1900);
FORCEADD TAP..1
(2475 2000);
FORCEPROP 3 LASTPIN (2425 2000) SIG_NAME M_H_CPU0_SA_CA<2>
J 0
(2435 2010);
DISPLAY 0.659574 (2435 2010);
PAINT MONO (2435 2010);
DISPLAY INVISIBLE (2435 2010);
FORCEPROP 1 LASTPIN (2425 2000) BN 2
J 0
(2413 2008);
DISPLAY 0.680851 (2413 2008);
PAINT GREEN (2413 2008);
FORCEPROP 2 LAST CDS_LIB standard
J 0
(2475 2000);
DISPLAY INVISIBLE (2475 2000);
FORCEPROP 1 LAST BODY_TYPE PLUMBING
J 0
(2475 2050);
DISPLAY 0.872340 (2475 2050);
PAINT GREEN (2475 2050);
DISPLAY INVISIBLE (2475 2050);
FORCEPROP 1 LAST HDL_TAP TRUE
J 0
(2800 1875);
DISPLAY 0.872340 (2800 1875);
DISPLAY INVISIBLE (2800 1875);
FORCEPROP 1 LAST PATH I113
J 0
(2473 2000);
DISPLAY 0.872340 (2473 2000);
PAINT GREEN (2473 2000);
DISPLAY INVISIBLE (2473 2000);
FORCEADD TAP..1
(2475 1950);
FORCEPROP 3 LASTPIN (2425 1950) SIG_NAME M_H_CPU0_SA_CA<1>
J 0
(2435 1960);
DISPLAY 0.659574 (2435 1960);
PAINT MONO (2435 1960);
DISPLAY INVISIBLE (2435 1960);
FORCEPROP 1 LASTPIN (2425 1950) BN 1
J 0
(2413 1958);
DISPLAY 0.680851 (2413 1958);
PAINT GREEN (2413 1958);
FORCEPROP 2 LAST CDS_LIB standard
J 0
(2475 1950);
DISPLAY INVISIBLE (2475 1950);
FORCEPROP 1 LAST BODY_TYPE PLUMBING
J 0
(2475 2000);
DISPLAY 0.872340 (2475 2000);
PAINT GREEN (2475 2000);
DISPLAY INVISIBLE (2475 2000);
FORCEPROP 1 LAST HDL_TAP TRUE
J 0
(2800 1825);
DISPLAY 0.872340 (2800 1825);
DISPLAY INVISIBLE (2800 1825);
FORCEPROP 1 LAST PATH I114
J 0
(2473 1950);
DISPLAY 0.872340 (2473 1950);
PAINT GREEN (2473 1950);
DISPLAY INVISIBLE (2473 1950);
FORCEADD TAP..1
(2475 2050);
FORCEPROP 3 LASTPIN (2425 2050) SIG_NAME M_H_CPU0_SA_CA<3>
J 0
(2435 2060);
DISPLAY 0.659574 (2435 2060);
PAINT MONO (2435 2060);
DISPLAY INVISIBLE (2435 2060);
FORCEPROP 1 LASTPIN (2425 2050) BN 3
J 0
(2413 2058);
DISPLAY 0.680851 (2413 2058);
PAINT GREEN (2413 2058);
FORCEPROP 2 LAST CDS_LIB standard
J 0
(2475 2050);
DISPLAY INVISIBLE (2475 2050);
FORCEPROP 1 LAST BODY_TYPE PLUMBING
J 0
(2475 2100);
DISPLAY 0.872340 (2475 2100);
PAINT GREEN (2475 2100);
DISPLAY INVISIBLE (2475 2100);
FORCEPROP 1 LAST HDL_TAP TRUE
J 0
(2800 1925);
DISPLAY 0.872340 (2800 1925);
DISPLAY INVISIBLE (2800 1925);
FORCEPROP 1 LAST PATH I115
J 0
(2473 2050);
DISPLAY 0.872340 (2473 2050);
PAINT GREEN (2473 2050);
DISPLAY INVISIBLE (2473 2050);
FORCEADD TAP..1
(2475 2150);
FORCEPROP 3 LASTPIN (2425 2150) SIG_NAME M_H_CPU0_SA_CA<5>
J 0
(2435 2160);
DISPLAY 0.659574 (2435 2160);
PAINT MONO (2435 2160);
DISPLAY INVISIBLE (2435 2160);
FORCEPROP 1 LASTPIN (2425 2150) BN 5
J 0
(2413 2158);
DISPLAY 0.680851 (2413 2158);
PAINT GREEN (2413 2158);
FORCEPROP 2 LAST CDS_LIB standard
J 0
(2475 2150);
DISPLAY INVISIBLE (2475 2150);
FORCEPROP 1 LAST BODY_TYPE PLUMBING
J 0
(2475 2200);
DISPLAY 0.872340 (2475 2200);
PAINT GREEN (2475 2200);
DISPLAY INVISIBLE (2475 2200);
FORCEPROP 1 LAST HDL_TAP TRUE
J 0
(2800 2025);
DISPLAY 0.872340 (2800 2025);
DISPLAY INVISIBLE (2800 2025);
FORCEPROP 1 LAST PATH I116
J 0
(2473 2150);
DISPLAY 0.872340 (2473 2150);
PAINT GREEN (2473 2150);
DISPLAY INVISIBLE (2473 2150);
FORCEADD TAP..1
(2475 2100);
FORCEPROP 3 LASTPIN (2425 2100) SIG_NAME M_H_CPU0_SA_CA<4>
J 0
(2435 2110);
DISPLAY 0.659574 (2435 2110);
PAINT MONO (2435 2110);
DISPLAY INVISIBLE (2435 2110);
FORCEPROP 1 LASTPIN (2425 2100) BN 4
J 0
(2413 2108);
DISPLAY 0.680851 (2413 2108);
PAINT GREEN (2413 2108);
FORCEPROP 2 LAST CDS_LIB standard
J 0
(2475 2100);
DISPLAY INVISIBLE (2475 2100);
FORCEPROP 1 LAST BODY_TYPE PLUMBING
J 0
(2475 2150);
DISPLAY 0.872340 (2475 2150);
PAINT GREEN (2475 2150);
DISPLAY INVISIBLE (2475 2150);
FORCEPROP 1 LAST HDL_TAP TRUE
J 0
(2800 1975);
DISPLAY 0.872340 (2800 1975);
DISPLAY INVISIBLE (2800 1975);
FORCEPROP 1 LAST PATH I117
J 0
(2473 2100);
DISPLAY 0.872340 (2473 2100);
PAINT GREEN (2473 2100);
DISPLAY INVISIBLE (2473 2100);
FORCEADD TAP..1
(2475 2200);
FORCEPROP 3 LASTPIN (2425 2200) SIG_NAME M_H_CPU0_SA_CA<6>
J 0
(2435 2210);
DISPLAY 0.659574 (2435 2210);
PAINT MONO (2435 2210);
DISPLAY INVISIBLE (2435 2210);
FORCEPROP 1 LASTPIN (2425 2200) BN 6
J 0
(2413 2208);
DISPLAY 0.680851 (2413 2208);
PAINT GREEN (2413 2208);
FORCEPROP 2 LAST CDS_LIB standard
J 0
(2475 2200);
DISPLAY INVISIBLE (2475 2200);
FORCEPROP 1 LAST BODY_TYPE PLUMBING
J 0
(2475 2250);
DISPLAY 0.872340 (2475 2250);
PAINT GREEN (2475 2250);
DISPLAY INVISIBLE (2475 2250);
FORCEPROP 1 LAST HDL_TAP TRUE
J 0
(2800 2075);
DISPLAY 0.872340 (2800 2075);
DISPLAY INVISIBLE (2800 2075);
FORCEPROP 1 LAST PATH I118
J 0
(2473 2200);
DISPLAY 0.872340 (2473 2200);
PAINT GREEN (2473 2200);
DISPLAY INVISIBLE (2473 2200);
FORCEADD TAP..1
(2475 2350);
FORCEPROP 3 LASTPIN (2425 2350) SIG_NAME M_H_CPU0_SB_DQS_DN<0>
J 0
(2435 2360);
DISPLAY 0.659574 (2435 2360);
PAINT MONO (2435 2360);
DISPLAY INVISIBLE (2435 2360);
FORCEPROP 1 LASTPIN (2425 2350) BN 0
J 0
(2413 2358);
DISPLAY 0.680851 (2413 2358);
PAINT GREEN (2413 2358);
FORCEPROP 2 LAST CDS_LIB standard
J 0
(2475 2350);
DISPLAY INVISIBLE (2475 2350);
FORCEPROP 1 LAST BODY_TYPE PLUMBING
J 0
(2475 2400);
DISPLAY 0.872340 (2475 2400);
PAINT GREEN (2475 2400);
DISPLAY INVISIBLE (2475 2400);
FORCEPROP 1 LAST HDL_TAP TRUE
J 0
(2800 2225);
DISPLAY 0.872340 (2800 2225);
DISPLAY INVISIBLE (2800 2225);
FORCEPROP 1 LAST PATH I119
J 0
(2473 2350);
DISPLAY 0.872340 (2473 2350);
PAINT GREEN (2473 2350);
DISPLAY INVISIBLE (2473 2350);
FORCEADD TAP..1
R 2
(-950 750);
FORCEPROP 3 LASTPIN (-900 750) SIG_NAME M_H_CPU0_SB_CB<4>
J 0
(-890 760);
DISPLAY 0.659574 (-890 760);
PAINT MONO (-890 760);
DISPLAY INVISIBLE (-890 760);
FORCEPROP 1 LASTPIN (-900 750) BN 4
J 2
(-888 758);
DISPLAY 0.680851 (-888 758);
PAINT GREEN (-888 758);
FORCEPROP 2 LAST CDS_LIB standard
J 0
(-950 750);
DISPLAY INVISIBLE (-950 750);
FORCEPROP 1 LAST BODY_TYPE PLUMBING
J 2
(-950 800);
DISPLAY 0.872340 (-950 800);
PAINT GREEN (-950 800);
DISPLAY INVISIBLE (-950 800);
FORCEPROP 1 LAST HDL_TAP TRUE
J 2
(-1275 625);
DISPLAY 0.872340 (-1275 625);
DISPLAY INVISIBLE (-1275 625);
FORCEPROP 1 LAST PATH I12
J 2
(-948 750);
DISPLAY 0.872340 (-948 750);
PAINT GREEN (-948 750);
DISPLAY INVISIBLE (-948 750);
FORCEADD TAP..1
(2475 2400);
FORCEPROP 3 LASTPIN (2425 2400) SIG_NAME M_H_CPU0_SB_DQS_DN<1>
J 0
(2435 2410);
DISPLAY 0.659574 (2435 2410);
PAINT MONO (2435 2410);
DISPLAY INVISIBLE (2435 2410);
FORCEPROP 1 LASTPIN (2425 2400) BN 1
J 0
(2413 2408);
DISPLAY 0.680851 (2413 2408);
PAINT GREEN (2413 2408);
FORCEPROP 2 LAST CDS_LIB standard
J 0
(2475 2400);
DISPLAY INVISIBLE (2475 2400);
FORCEPROP 1 LAST BODY_TYPE PLUMBING
J 0
(2475 2450);
DISPLAY 0.872340 (2475 2450);
PAINT GREEN (2475 2450);
DISPLAY INVISIBLE (2475 2450);
FORCEPROP 1 LAST HDL_TAP TRUE
J 0
(2800 2275);
DISPLAY 0.872340 (2800 2275);
DISPLAY INVISIBLE (2800 2275);
FORCEPROP 1 LAST PATH I120
J 0
(2473 2400);
DISPLAY 0.872340 (2473 2400);
PAINT GREEN (2473 2400);
DISPLAY INVISIBLE (2473 2400);
FORCEADD TAP..1
(2475 2450);
FORCEPROP 3 LASTPIN (2425 2450) SIG_NAME M_H_CPU0_SB_DQS_DN<2>
J 0
(2435 2460);
DISPLAY 0.659574 (2435 2460);
PAINT MONO (2435 2460);
DISPLAY INVISIBLE (2435 2460);
FORCEPROP 1 LASTPIN (2425 2450) BN 2
J 0
(2413 2458);
DISPLAY 0.680851 (2413 2458);
PAINT GREEN (2413 2458);
FORCEPROP 2 LAST CDS_LIB standard
J 0
(2475 2450);
DISPLAY INVISIBLE (2475 2450);
FORCEPROP 1 LAST BODY_TYPE PLUMBING
J 0
(2475 2500);
DISPLAY 0.872340 (2475 2500);
PAINT GREEN (2475 2500);
DISPLAY INVISIBLE (2475 2500);
FORCEPROP 1 LAST HDL_TAP TRUE
J 0
(2800 2325);
DISPLAY 0.872340 (2800 2325);
DISPLAY INVISIBLE (2800 2325);
FORCEPROP 1 LAST PATH I121
J 0
(2473 2450);
DISPLAY 0.872340 (2473 2450);
PAINT GREEN (2473 2450);
DISPLAY INVISIBLE (2473 2450);
FORCEADD TAP..1
(2475 2500);
FORCEPROP 3 LASTPIN (2425 2500) SIG_NAME M_H_CPU0_SB_DQS_DN<3>
J 0
(2435 2510);
DISPLAY 0.659574 (2435 2510);
PAINT MONO (2435 2510);
DISPLAY INVISIBLE (2435 2510);
FORCEPROP 1 LASTPIN (2425 2500) BN 3
J 0
(2413 2508);
DISPLAY 0.680851 (2413 2508);
PAINT GREEN (2413 2508);
FORCEPROP 2 LAST CDS_LIB standard
J 0
(2475 2500);
DISPLAY INVISIBLE (2475 2500);
FORCEPROP 1 LAST BODY_TYPE PLUMBING
J 0
(2475 2550);
DISPLAY 0.872340 (2475 2550);
PAINT GREEN (2475 2550);
DISPLAY INVISIBLE (2475 2550);
FORCEPROP 1 LAST HDL_TAP TRUE
J 0
(2800 2375);
DISPLAY 0.872340 (2800 2375);
DISPLAY INVISIBLE (2800 2375);
FORCEPROP 1 LAST PATH I122
J 0
(2473 2500);
DISPLAY 0.872340 (2473 2500);
PAINT GREEN (2473 2500);
DISPLAY INVISIBLE (2473 2500);
FORCEADD TAP..1
(2475 2550);
FORCEPROP 3 LASTPIN (2425 2550) SIG_NAME M_H_CPU0_SB_DQS_DN<4>
J 0
(2435 2560);
DISPLAY 0.659574 (2435 2560);
PAINT MONO (2435 2560);
DISPLAY INVISIBLE (2435 2560);
FORCEPROP 1 LASTPIN (2425 2550) BN 4
J 0
(2413 2558);
DISPLAY 0.680851 (2413 2558);
PAINT GREEN (2413 2558);
FORCEPROP 2 LAST CDS_LIB standard
J 0
(2475 2550);
DISPLAY INVISIBLE (2475 2550);
FORCEPROP 1 LAST BODY_TYPE PLUMBING
J 0
(2475 2600);
DISPLAY 0.872340 (2475 2600);
PAINT GREEN (2475 2600);
DISPLAY INVISIBLE (2475 2600);
FORCEPROP 1 LAST HDL_TAP TRUE
J 0
(2800 2425);
DISPLAY 0.872340 (2800 2425);
DISPLAY INVISIBLE (2800 2425);
FORCEPROP 1 LAST PATH I123
J 0
(2473 2550);
DISPLAY 0.872340 (2473 2550);
PAINT GREEN (2473 2550);
DISPLAY INVISIBLE (2473 2550);
FORCEADD TAP..1
(2475 2650);
FORCEPROP 3 LASTPIN (2425 2650) SIG_NAME M_H_CPU0_SB_DQS_DN<6>
J 0
(2435 2660);
DISPLAY 0.659574 (2435 2660);
PAINT MONO (2435 2660);
DISPLAY INVISIBLE (2435 2660);
FORCEPROP 1 LASTPIN (2425 2650) BN 6
J 0
(2413 2658);
DISPLAY 0.680851 (2413 2658);
PAINT GREEN (2413 2658);
FORCEPROP 2 LAST CDS_LIB standard
J 0
(2475 2650);
DISPLAY INVISIBLE (2475 2650);
FORCEPROP 1 LAST BODY_TYPE PLUMBING
J 0
(2475 2700);
DISPLAY 0.872340 (2475 2700);
PAINT GREEN (2475 2700);
DISPLAY INVISIBLE (2475 2700);
FORCEPROP 1 LAST HDL_TAP TRUE
J 0
(2800 2525);
DISPLAY 0.872340 (2800 2525);
DISPLAY INVISIBLE (2800 2525);
FORCEPROP 1 LAST PATH I124
J 0
(2473 2650);
DISPLAY 0.872340 (2473 2650);
PAINT GREEN (2473 2650);
DISPLAY INVISIBLE (2473 2650);
FORCEADD TAP..1
(2475 2600);
FORCEPROP 3 LASTPIN (2425 2600) SIG_NAME M_H_CPU0_SB_DQS_DN<5>
J 0
(2435 2610);
DISPLAY 0.659574 (2435 2610);
PAINT MONO (2435 2610);
DISPLAY INVISIBLE (2435 2610);
FORCEPROP 1 LASTPIN (2425 2600) BN 5
J 0
(2413 2608);
DISPLAY 0.680851 (2413 2608);
PAINT GREEN (2413 2608);
FORCEPROP 2 LAST CDS_LIB standard
J 0
(2475 2600);
DISPLAY INVISIBLE (2475 2600);
FORCEPROP 1 LAST BODY_TYPE PLUMBING
J 0
(2475 2650);
DISPLAY 0.872340 (2475 2650);
PAINT GREEN (2475 2650);
DISPLAY INVISIBLE (2475 2650);
FORCEPROP 1 LAST HDL_TAP TRUE
J 0
(2800 2475);
DISPLAY 0.872340 (2800 2475);
DISPLAY INVISIBLE (2800 2475);
FORCEPROP 1 LAST PATH I125
J 0
(2473 2600);
DISPLAY 0.872340 (2473 2600);
PAINT GREEN (2473 2600);
DISPLAY INVISIBLE (2473 2600);
FORCEADD TAP..1
(2475 2800);
FORCEPROP 3 LASTPIN (2425 2800) SIG_NAME M_H_CPU0_SB_DQS_DN<9>
J 0
(2435 2810);
DISPLAY 0.659574 (2435 2810);
PAINT MONO (2435 2810);
DISPLAY INVISIBLE (2435 2810);
FORCEPROP 1 LASTPIN (2425 2800) BN 9
J 0
(2413 2808);
DISPLAY 0.680851 (2413 2808);
PAINT GREEN (2413 2808);
FORCEPROP 2 LAST CDS_LIB standard
J 0
(2475 2800);
DISPLAY INVISIBLE (2475 2800);
FORCEPROP 1 LAST BODY_TYPE PLUMBING
J 0
(2475 2850);
DISPLAY 0.872340 (2475 2850);
PAINT GREEN (2475 2850);
DISPLAY INVISIBLE (2475 2850);
FORCEPROP 1 LAST HDL_TAP TRUE
J 0
(2800 2675);
DISPLAY 0.872340 (2800 2675);
DISPLAY INVISIBLE (2800 2675);
FORCEPROP 1 LAST PATH I126
J 0
(2473 2800);
DISPLAY 0.872340 (2473 2800);
PAINT GREEN (2473 2800);
DISPLAY INVISIBLE (2473 2800);
FORCEADD TAP..1
(2475 2750);
FORCEPROP 3 LASTPIN (2425 2750) SIG_NAME M_H_CPU0_SB_DQS_DN<8>
J 0
(2435 2760);
DISPLAY 0.659574 (2435 2760);
PAINT MONO (2435 2760);
DISPLAY INVISIBLE (2435 2760);
FORCEPROP 1 LASTPIN (2425 2750) BN 8
J 0
(2413 2758);
DISPLAY 0.680851 (2413 2758);
PAINT GREEN (2413 2758);
FORCEPROP 2 LAST CDS_LIB standard
J 0
(2475 2750);
DISPLAY INVISIBLE (2475 2750);
FORCEPROP 1 LAST BODY_TYPE PLUMBING
J 0
(2475 2800);
DISPLAY 0.872340 (2475 2800);
PAINT GREEN (2475 2800);
DISPLAY INVISIBLE (2475 2800);
FORCEPROP 1 LAST HDL_TAP TRUE
J 0
(2800 2625);
DISPLAY 0.872340 (2800 2625);
DISPLAY INVISIBLE (2800 2625);
FORCEPROP 1 LAST PATH I127
J 0
(2473 2750);
DISPLAY 0.872340 (2473 2750);
PAINT GREEN (2473 2750);
DISPLAY INVISIBLE (2473 2750);
FORCEADD TAP..1
(2475 2700);
FORCEPROP 3 LASTPIN (2425 2700) SIG_NAME M_H_CPU0_SB_DQS_DN<7>
J 0
(2435 2710);
DISPLAY 0.659574 (2435 2710);
PAINT MONO (2435 2710);
DISPLAY INVISIBLE (2435 2710);
FORCEPROP 1 LASTPIN (2425 2700) BN 7
J 0
(2413 2708);
DISPLAY 0.680851 (2413 2708);
PAINT GREEN (2413 2708);
FORCEPROP 2 LAST CDS_LIB standard
J 0
(2475 2700);
DISPLAY INVISIBLE (2475 2700);
FORCEPROP 1 LAST BODY_TYPE PLUMBING
J 0
(2475 2750);
DISPLAY 0.872340 (2475 2750);
PAINT GREEN (2475 2750);
DISPLAY INVISIBLE (2475 2750);
FORCEPROP 1 LAST HDL_TAP TRUE
J 0
(2800 2575);
DISPLAY 0.872340 (2800 2575);
DISPLAY INVISIBLE (2800 2575);
FORCEPROP 1 LAST PATH I128
J 0
(2473 2700);
DISPLAY 0.872340 (2473 2700);
PAINT GREEN (2473 2700);
DISPLAY INVISIBLE (2473 2700);
FORCEADD TAP..1
(2475 2900);
FORCEPROP 3 LASTPIN (2425 2900) SIG_NAME M_H_CPU0_SB_DQS_DP<0>
J 0
(2435 2910);
DISPLAY 0.659574 (2435 2910);
PAINT MONO (2435 2910);
DISPLAY INVISIBLE (2435 2910);
FORCEPROP 1 LASTPIN (2425 2900) BN 0
J 0
(2413 2908);
DISPLAY 0.680851 (2413 2908);
PAINT GREEN (2413 2908);
FORCEPROP 2 LAST CDS_LIB standard
J 0
(2475 2900);
DISPLAY INVISIBLE (2475 2900);
FORCEPROP 1 LAST BODY_TYPE PLUMBING
J 0
(2475 2950);
DISPLAY 0.872340 (2475 2950);
PAINT GREEN (2475 2950);
DISPLAY INVISIBLE (2475 2950);
FORCEPROP 1 LAST HDL_TAP TRUE
J 0
(2800 2775);
DISPLAY 0.872340 (2800 2775);
DISPLAY INVISIBLE (2800 2775);
FORCEPROP 1 LAST PATH I129
J 0
(2473 2900);
DISPLAY 0.872340 (2473 2900);
PAINT GREEN (2473 2900);
DISPLAY INVISIBLE (2473 2900);
FORCEADD TAP..1
R 2
(-950 700);
FORCEPROP 3 LASTPIN (-900 700) SIG_NAME M_H_CPU0_SB_CB<3>
J 0
(-890 710);
DISPLAY 0.659574 (-890 710);
PAINT MONO (-890 710);
DISPLAY INVISIBLE (-890 710);
FORCEPROP 1 LASTPIN (-900 700) BN 3
J 2
(-888 708);
DISPLAY 0.680851 (-888 708);
PAINT GREEN (-888 708);
FORCEPROP 2 LAST CDS_LIB standard
J 0
(-950 700);
DISPLAY INVISIBLE (-950 700);
FORCEPROP 1 LAST BODY_TYPE PLUMBING
J 2
(-950 750);
DISPLAY 0.872340 (-950 750);
PAINT GREEN (-950 750);
DISPLAY INVISIBLE (-950 750);
FORCEPROP 1 LAST HDL_TAP TRUE
J 2
(-1275 575);
DISPLAY 0.872340 (-1275 575);
DISPLAY INVISIBLE (-1275 575);
FORCEPROP 1 LAST PATH I13
J 2
(-948 700);
DISPLAY 0.872340 (-948 700);
PAINT GREEN (-948 700);
DISPLAY INVISIBLE (-948 700);
FORCEADD TAP..1
(2475 2950);
FORCEPROP 3 LASTPIN (2425 2950) SIG_NAME M_H_CPU0_SB_DQS_DP<1>
J 0
(2435 2960);
DISPLAY 0.659574 (2435 2960);
PAINT MONO (2435 2960);
DISPLAY INVISIBLE (2435 2960);
FORCEPROP 1 LASTPIN (2425 2950) BN 1
J 0
(2413 2958);
DISPLAY 0.680851 (2413 2958);
PAINT GREEN (2413 2958);
FORCEPROP 2 LAST CDS_LIB standard
J 0
(2475 2950);
DISPLAY INVISIBLE (2475 2950);
FORCEPROP 1 LAST BODY_TYPE PLUMBING
J 0
(2475 3000);
DISPLAY 0.872340 (2475 3000);
PAINT GREEN (2475 3000);
DISPLAY INVISIBLE (2475 3000);
FORCEPROP 1 LAST HDL_TAP TRUE
J 0
(2800 2825);
DISPLAY 0.872340 (2800 2825);
DISPLAY INVISIBLE (2800 2825);
FORCEPROP 1 LAST PATH I130
J 0
(2473 2950);
DISPLAY 0.872340 (2473 2950);
PAINT GREEN (2473 2950);
DISPLAY INVISIBLE (2473 2950);
FORCEADD TAP..1
(2475 3000);
FORCEPROP 3 LASTPIN (2425 3000) SIG_NAME M_H_CPU0_SB_DQS_DP<2>
J 0
(2435 3010);
DISPLAY 0.659574 (2435 3010);
PAINT MONO (2435 3010);
DISPLAY INVISIBLE (2435 3010);
FORCEPROP 1 LASTPIN (2425 3000) BN 2
J 0
(2413 3008);
DISPLAY 0.680851 (2413 3008);
PAINT GREEN (2413 3008);
FORCEPROP 2 LAST CDS_LIB standard
J 0
(2475 3000);
DISPLAY INVISIBLE (2475 3000);
FORCEPROP 1 LAST BODY_TYPE PLUMBING
J 0
(2475 3050);
DISPLAY 0.872340 (2475 3050);
PAINT GREEN (2475 3050);
DISPLAY INVISIBLE (2475 3050);
FORCEPROP 1 LAST HDL_TAP TRUE
J 0
(2800 2875);
DISPLAY 0.872340 (2800 2875);
DISPLAY INVISIBLE (2800 2875);
FORCEPROP 1 LAST PATH I131
J 0
(2473 3000);
DISPLAY 0.872340 (2473 3000);
PAINT GREEN (2473 3000);
DISPLAY INVISIBLE (2473 3000);
FORCEADD TAP..1
(2475 3050);
FORCEPROP 3 LASTPIN (2425 3050) SIG_NAME M_H_CPU0_SB_DQS_DP<3>
J 0
(2435 3060);
DISPLAY 0.659574 (2435 3060);
PAINT MONO (2435 3060);
DISPLAY INVISIBLE (2435 3060);
FORCEPROP 1 LASTPIN (2425 3050) BN 3
J 0
(2413 3058);
DISPLAY 0.680851 (2413 3058);
PAINT GREEN (2413 3058);
FORCEPROP 2 LAST CDS_LIB standard
J 0
(2475 3050);
DISPLAY INVISIBLE (2475 3050);
FORCEPROP 1 LAST BODY_TYPE PLUMBING
J 0
(2475 3100);
DISPLAY 0.872340 (2475 3100);
PAINT GREEN (2475 3100);
DISPLAY INVISIBLE (2475 3100);
FORCEPROP 1 LAST HDL_TAP TRUE
J 0
(2800 2925);
DISPLAY 0.872340 (2800 2925);
DISPLAY INVISIBLE (2800 2925);
FORCEPROP 1 LAST PATH I132
J 0
(2473 3050);
DISPLAY 0.872340 (2473 3050);
PAINT GREEN (2473 3050);
DISPLAY INVISIBLE (2473 3050);
FORCEADD TAP..1
(2475 3200);
FORCEPROP 3 LASTPIN (2425 3200) SIG_NAME M_H_CPU0_SB_DQS_DP<6>
J 0
(2435 3210);
DISPLAY 0.659574 (2435 3210);
PAINT MONO (2435 3210);
DISPLAY INVISIBLE (2435 3210);
FORCEPROP 1 LASTPIN (2425 3200) BN 6
J 0
(2413 3208);
DISPLAY 0.680851 (2413 3208);
PAINT GREEN (2413 3208);
FORCEPROP 2 LAST CDS_LIB standard
J 0
(2475 3200);
DISPLAY INVISIBLE (2475 3200);
FORCEPROP 1 LAST BODY_TYPE PLUMBING
J 0
(2475 3250);
DISPLAY 0.872340 (2475 3250);
PAINT GREEN (2475 3250);
DISPLAY INVISIBLE (2475 3250);
FORCEPROP 1 LAST HDL_TAP TRUE
J 0
(2800 3075);
DISPLAY 0.872340 (2800 3075);
DISPLAY INVISIBLE (2800 3075);
FORCEPROP 1 LAST PATH I133
J 0
(2473 3200);
DISPLAY 0.872340 (2473 3200);
PAINT GREEN (2473 3200);
DISPLAY INVISIBLE (2473 3200);
FORCEADD TAP..1
(2475 3100);
FORCEPROP 3 LASTPIN (2425 3100) SIG_NAME M_H_CPU0_SB_DQS_DP<4>
J 0
(2435 3110);
DISPLAY 0.659574 (2435 3110);
PAINT MONO (2435 3110);
DISPLAY INVISIBLE (2435 3110);
FORCEPROP 1 LASTPIN (2425 3100) BN 4
J 0
(2413 3108);
DISPLAY 0.680851 (2413 3108);
PAINT GREEN (2413 3108);
FORCEPROP 2 LAST CDS_LIB standard
J 0
(2475 3100);
DISPLAY INVISIBLE (2475 3100);
FORCEPROP 1 LAST BODY_TYPE PLUMBING
J 0
(2475 3150);
DISPLAY 0.872340 (2475 3150);
PAINT GREEN (2475 3150);
DISPLAY INVISIBLE (2475 3150);
FORCEPROP 1 LAST HDL_TAP TRUE
J 0
(2800 2975);
DISPLAY 0.872340 (2800 2975);
DISPLAY INVISIBLE (2800 2975);
FORCEPROP 1 LAST PATH I134
J 0
(2473 3100);
DISPLAY 0.872340 (2473 3100);
PAINT GREEN (2473 3100);
DISPLAY INVISIBLE (2473 3100);
FORCEADD TAP..1
(2475 3150);
FORCEPROP 3 LASTPIN (2425 3150) SIG_NAME M_H_CPU0_SB_DQS_DP<5>
J 0
(2435 3160);
DISPLAY 0.659574 (2435 3160);
PAINT MONO (2435 3160);
DISPLAY INVISIBLE (2435 3160);
FORCEPROP 1 LASTPIN (2425 3150) BN 5
J 0
(2413 3158);
DISPLAY 0.680851 (2413 3158);
PAINT GREEN (2413 3158);
FORCEPROP 2 LAST CDS_LIB standard
J 0
(2475 3150);
DISPLAY INVISIBLE (2475 3150);
FORCEPROP 1 LAST BODY_TYPE PLUMBING
J 0
(2475 3200);
DISPLAY 0.872340 (2475 3200);
PAINT GREEN (2475 3200);
DISPLAY INVISIBLE (2475 3200);
FORCEPROP 1 LAST HDL_TAP TRUE
J 0
(2800 3025);
DISPLAY 0.872340 (2800 3025);
DISPLAY INVISIBLE (2800 3025);
FORCEPROP 1 LAST PATH I135
J 0
(2473 3150);
DISPLAY 0.872340 (2473 3150);
PAINT GREEN (2473 3150);
DISPLAY INVISIBLE (2473 3150);
FORCEADD TAP..1
(2475 3300);
FORCEPROP 3 LASTPIN (2425 3300) SIG_NAME M_H_CPU0_SB_DQS_DP<8>
J 0
(2435 3310);
DISPLAY 0.659574 (2435 3310);
PAINT MONO (2435 3310);
DISPLAY INVISIBLE (2435 3310);
FORCEPROP 1 LASTPIN (2425 3300) BN 8
J 0
(2413 3308);
DISPLAY 0.680851 (2413 3308);
PAINT GREEN (2413 3308);
FORCEPROP 2 LAST CDS_LIB standard
J 0
(2475 3300);
DISPLAY INVISIBLE (2475 3300);
FORCEPROP 1 LAST BODY_TYPE PLUMBING
J 0
(2475 3350);
DISPLAY 0.872340 (2475 3350);
PAINT GREEN (2475 3350);
DISPLAY INVISIBLE (2475 3350);
FORCEPROP 1 LAST HDL_TAP TRUE
J 0
(2800 3175);
DISPLAY 0.872340 (2800 3175);
DISPLAY INVISIBLE (2800 3175);
FORCEPROP 1 LAST PATH I136
J 0
(2473 3300);
DISPLAY 0.872340 (2473 3300);
PAINT GREEN (2473 3300);
DISPLAY INVISIBLE (2473 3300);
FORCEADD TAP..1
(2475 3350);
FORCEPROP 3 LASTPIN (2425 3350) SIG_NAME M_H_CPU0_SB_DQS_DP<9>
J 0
(2435 3360);
DISPLAY 0.659574 (2435 3360);
PAINT MONO (2435 3360);
DISPLAY INVISIBLE (2435 3360);
FORCEPROP 1 LASTPIN (2425 3350) BN 9
J 0
(2413 3358);
DISPLAY 0.680851 (2413 3358);
PAINT GREEN (2413 3358);
FORCEPROP 2 LAST CDS_LIB standard
J 0
(2475 3350);
DISPLAY INVISIBLE (2475 3350);
FORCEPROP 1 LAST BODY_TYPE PLUMBING
J 0
(2475 3400);
DISPLAY 0.872340 (2475 3400);
PAINT GREEN (2475 3400);
DISPLAY INVISIBLE (2475 3400);
FORCEPROP 1 LAST HDL_TAP TRUE
J 0
(2800 3225);
DISPLAY 0.872340 (2800 3225);
DISPLAY INVISIBLE (2800 3225);
FORCEPROP 1 LAST PATH I137
J 0
(2473 3350);
DISPLAY 0.872340 (2473 3350);
PAINT GREEN (2473 3350);
DISPLAY INVISIBLE (2473 3350);
FORCEADD TAP..1
(2475 3250);
FORCEPROP 3 LASTPIN (2425 3250) SIG_NAME M_H_CPU0_SB_DQS_DP<7>
J 0
(2435 3260);
DISPLAY 0.659574 (2435 3260);
PAINT MONO (2435 3260);
DISPLAY INVISIBLE (2435 3260);
FORCEPROP 1 LASTPIN (2425 3250) BN 7
J 0
(2413 3258);
DISPLAY 0.680851 (2413 3258);
PAINT GREEN (2413 3258);
FORCEPROP 2 LAST CDS_LIB standard
J 0
(2475 3250);
DISPLAY INVISIBLE (2475 3250);
FORCEPROP 1 LAST BODY_TYPE PLUMBING
J 0
(2475 3300);
DISPLAY 0.872340 (2475 3300);
PAINT GREEN (2475 3300);
DISPLAY INVISIBLE (2475 3300);
FORCEPROP 1 LAST HDL_TAP TRUE
J 0
(2800 3125);
DISPLAY 0.872340 (2800 3125);
DISPLAY INVISIBLE (2800 3125);
FORCEPROP 1 LAST PATH I138
J 0
(2473 3250);
DISPLAY 0.872340 (2473 3250);
PAINT GREEN (2473 3250);
DISPLAY INVISIBLE (2473 3250);
FORCEADD TAP..1
(2475 3550);
FORCEPROP 3 LASTPIN (2425 3550) SIG_NAME M_H_CPU0_SA_DQS_DN<1>
J 0
(2435 3560);
DISPLAY 0.659574 (2435 3560);
PAINT MONO (2435 3560);
DISPLAY INVISIBLE (2435 3560);
FORCEPROP 1 LASTPIN (2425 3550) BN 1
J 0
(2413 3558);
DISPLAY 0.680851 (2413 3558);
PAINT GREEN (2413 3558);
FORCEPROP 2 LAST CDS_LIB standard
J 0
(2475 3550);
DISPLAY INVISIBLE (2475 3550);
FORCEPROP 1 LAST BODY_TYPE PLUMBING
J 0
(2475 3600);
DISPLAY 0.872340 (2475 3600);
PAINT GREEN (2475 3600);
DISPLAY INVISIBLE (2475 3600);
FORCEPROP 1 LAST HDL_TAP TRUE
J 0
(2800 3425);
DISPLAY 0.872340 (2800 3425);
DISPLAY INVISIBLE (2800 3425);
FORCEPROP 1 LAST PATH I139
J 0
(2473 3550);
DISPLAY 0.872340 (2473 3550);
PAINT GREEN (2473 3550);
DISPLAY INVISIBLE (2473 3550);
FORCEADD TAP..1
R 2
(-950 850);
FORCEPROP 3 LASTPIN (-900 850) SIG_NAME M_H_CPU0_SB_CB<6>
J 0
(-890 860);
DISPLAY 0.659574 (-890 860);
PAINT MONO (-890 860);
DISPLAY INVISIBLE (-890 860);
FORCEPROP 1 LASTPIN (-900 850) BN 6
J 2
(-888 858);
DISPLAY 0.680851 (-888 858);
PAINT GREEN (-888 858);
FORCEPROP 2 LAST CDS_LIB standard
J 0
(-950 850);
DISPLAY INVISIBLE (-950 850);
FORCEPROP 1 LAST BODY_TYPE PLUMBING
J 2
(-950 900);
DISPLAY 0.872340 (-950 900);
PAINT GREEN (-950 900);
DISPLAY INVISIBLE (-950 900);
FORCEPROP 1 LAST HDL_TAP TRUE
J 2
(-1275 725);
DISPLAY 0.872340 (-1275 725);
DISPLAY INVISIBLE (-1275 725);
FORCEPROP 1 LAST PATH I14
J 2
(-948 850);
DISPLAY 0.872340 (-948 850);
PAINT GREEN (-948 850);
DISPLAY INVISIBLE (-948 850);
FORCEADD TAP..1
(2475 3500);
FORCEPROP 3 LASTPIN (2425 3500) SIG_NAME M_H_CPU0_SA_DQS_DN<0>
J 0
(2435 3510);
DISPLAY 0.659574 (2435 3510);
PAINT MONO (2435 3510);
DISPLAY INVISIBLE (2435 3510);
FORCEPROP 1 LASTPIN (2425 3500) BN 0
J 0
(2413 3508);
DISPLAY 0.680851 (2413 3508);
PAINT GREEN (2413 3508);
FORCEPROP 2 LAST CDS_LIB standard
J 0
(2475 3500);
DISPLAY INVISIBLE (2475 3500);
FORCEPROP 1 LAST BODY_TYPE PLUMBING
J 0
(2475 3550);
DISPLAY 0.872340 (2475 3550);
PAINT GREEN (2475 3550);
DISPLAY INVISIBLE (2475 3550);
FORCEPROP 1 LAST HDL_TAP TRUE
J 0
(2800 3375);
DISPLAY 0.872340 (2800 3375);
DISPLAY INVISIBLE (2800 3375);
FORCEPROP 1 LAST PATH I140
J 0
(2473 3500);
DISPLAY 0.872340 (2473 3500);
PAINT GREEN (2473 3500);
DISPLAY INVISIBLE (2473 3500);
FORCEADD TAP..1
(2475 3700);
FORCEPROP 3 LASTPIN (2425 3700) SIG_NAME M_H_CPU0_SA_DQS_DN<4>
J 0
(2435 3710);
DISPLAY 0.659574 (2435 3710);
PAINT MONO (2435 3710);
DISPLAY INVISIBLE (2435 3710);
FORCEPROP 1 LASTPIN (2425 3700) BN 4
J 0
(2413 3708);
DISPLAY 0.680851 (2413 3708);
PAINT GREEN (2413 3708);
FORCEPROP 2 LAST CDS_LIB standard
J 0
(2475 3700);
DISPLAY INVISIBLE (2475 3700);
FORCEPROP 1 LAST BODY_TYPE PLUMBING
J 0
(2475 3750);
DISPLAY 0.872340 (2475 3750);
PAINT GREEN (2475 3750);
DISPLAY INVISIBLE (2475 3750);
FORCEPROP 1 LAST HDL_TAP TRUE
J 0
(2800 3575);
DISPLAY 0.872340 (2800 3575);
DISPLAY INVISIBLE (2800 3575);
FORCEPROP 1 LAST PATH I141
J 0
(2473 3700);
DISPLAY 0.872340 (2473 3700);
PAINT GREEN (2473 3700);
DISPLAY INVISIBLE (2473 3700);
FORCEADD TAP..1
(2475 3600);
FORCEPROP 3 LASTPIN (2425 3600) SIG_NAME M_H_CPU0_SA_DQS_DN<2>
J 0
(2435 3610);
DISPLAY 0.659574 (2435 3610);
PAINT MONO (2435 3610);
DISPLAY INVISIBLE (2435 3610);
FORCEPROP 1 LASTPIN (2425 3600) BN 2
J 0
(2413 3608);
DISPLAY 0.680851 (2413 3608);
PAINT GREEN (2413 3608);
FORCEPROP 2 LAST CDS_LIB standard
J 0
(2475 3600);
DISPLAY INVISIBLE (2475 3600);
FORCEPROP 1 LAST BODY_TYPE PLUMBING
J 0
(2475 3650);
DISPLAY 0.872340 (2475 3650);
PAINT GREEN (2475 3650);
DISPLAY INVISIBLE (2475 3650);
FORCEPROP 1 LAST HDL_TAP TRUE
J 0
(2800 3475);
DISPLAY 0.872340 (2800 3475);
DISPLAY INVISIBLE (2800 3475);
FORCEPROP 1 LAST PATH I142
J 0
(2473 3600);
DISPLAY 0.872340 (2473 3600);
PAINT GREEN (2473 3600);
DISPLAY INVISIBLE (2473 3600);
FORCEADD TAP..1
(2475 3650);
FORCEPROP 3 LASTPIN (2425 3650) SIG_NAME M_H_CPU0_SA_DQS_DN<3>
J 0
(2435 3660);
DISPLAY 0.659574 (2435 3660);
PAINT MONO (2435 3660);
DISPLAY INVISIBLE (2435 3660);
FORCEPROP 1 LASTPIN (2425 3650) BN 3
J 0
(2413 3658);
DISPLAY 0.680851 (2413 3658);
PAINT GREEN (2413 3658);
FORCEPROP 2 LAST CDS_LIB standard
J 0
(2475 3650);
DISPLAY INVISIBLE (2475 3650);
FORCEPROP 1 LAST BODY_TYPE PLUMBING
J 0
(2475 3700);
DISPLAY 0.872340 (2475 3700);
PAINT GREEN (2475 3700);
DISPLAY INVISIBLE (2475 3700);
FORCEPROP 1 LAST HDL_TAP TRUE
J 0
(2800 3525);
DISPLAY 0.872340 (2800 3525);
DISPLAY INVISIBLE (2800 3525);
FORCEPROP 1 LAST PATH I143
J 0
(2473 3650);
DISPLAY 0.872340 (2473 3650);
PAINT GREEN (2473 3650);
DISPLAY INVISIBLE (2473 3650);
FORCEADD TAP..1
(2475 3750);
FORCEPROP 3 LASTPIN (2425 3750) SIG_NAME M_H_CPU0_SA_DQS_DN<5>
J 0
(2435 3760);
DISPLAY 0.659574 (2435 3760);
PAINT MONO (2435 3760);
DISPLAY INVISIBLE (2435 3760);
FORCEPROP 1 LASTPIN (2425 3750) BN 5
J 0
(2413 3758);
DISPLAY 0.680851 (2413 3758);
PAINT GREEN (2413 3758);
FORCEPROP 2 LAST CDS_LIB standard
J 0
(2475 3750);
DISPLAY INVISIBLE (2475 3750);
FORCEPROP 1 LAST BODY_TYPE PLUMBING
J 0
(2475 3800);
DISPLAY 0.872340 (2475 3800);
PAINT GREEN (2475 3800);
DISPLAY INVISIBLE (2475 3800);
FORCEPROP 1 LAST HDL_TAP TRUE
J 0
(2800 3625);
DISPLAY 0.872340 (2800 3625);
DISPLAY INVISIBLE (2800 3625);
FORCEPROP 1 LAST PATH I144
J 0
(2473 3750);
DISPLAY 0.872340 (2473 3750);
PAINT GREEN (2473 3750);
DISPLAY INVISIBLE (2473 3750);
FORCEADD TAP..1
(2475 3800);
FORCEPROP 3 LASTPIN (2425 3800) SIG_NAME M_H_CPU0_SA_DQS_DN<6>
J 0
(2435 3810);
DISPLAY 0.659574 (2435 3810);
PAINT MONO (2435 3810);
DISPLAY INVISIBLE (2435 3810);
FORCEPROP 1 LASTPIN (2425 3800) BN 6
J 0
(2413 3808);
DISPLAY 0.680851 (2413 3808);
PAINT GREEN (2413 3808);
FORCEPROP 2 LAST CDS_LIB standard
J 0
(2475 3800);
DISPLAY INVISIBLE (2475 3800);
FORCEPROP 1 LAST BODY_TYPE PLUMBING
J 0
(2475 3850);
DISPLAY 0.872340 (2475 3850);
PAINT GREEN (2475 3850);
DISPLAY INVISIBLE (2475 3850);
FORCEPROP 1 LAST HDL_TAP TRUE
J 0
(2800 3675);
DISPLAY 0.872340 (2800 3675);
DISPLAY INVISIBLE (2800 3675);
FORCEPROP 1 LAST PATH I145
J 0
(2473 3800);
DISPLAY 0.872340 (2473 3800);
PAINT GREEN (2473 3800);
DISPLAY INVISIBLE (2473 3800);
FORCEADD TAP..1
(2475 3850);
FORCEPROP 3 LASTPIN (2425 3850) SIG_NAME M_H_CPU0_SA_DQS_DN<7>
J 0
(2435 3860);
DISPLAY 0.659574 (2435 3860);
PAINT MONO (2435 3860);
DISPLAY INVISIBLE (2435 3860);
FORCEPROP 1 LASTPIN (2425 3850) BN 7
J 0
(2413 3858);
DISPLAY 0.680851 (2413 3858);
PAINT GREEN (2413 3858);
FORCEPROP 2 LAST CDS_LIB standard
J 0
(2475 3850);
DISPLAY INVISIBLE (2475 3850);
FORCEPROP 1 LAST BODY_TYPE PLUMBING
J 0
(2475 3900);
DISPLAY 0.872340 (2475 3900);
PAINT GREEN (2475 3900);
DISPLAY INVISIBLE (2475 3900);
FORCEPROP 1 LAST HDL_TAP TRUE
J 0
(2800 3725);
DISPLAY 0.872340 (2800 3725);
DISPLAY INVISIBLE (2800 3725);
FORCEPROP 1 LAST PATH I146
J 0
(2473 3850);
DISPLAY 0.872340 (2473 3850);
PAINT GREEN (2473 3850);
DISPLAY INVISIBLE (2473 3850);
FORCEADD TAP..1
(2475 3950);
FORCEPROP 3 LASTPIN (2425 3950) SIG_NAME M_H_CPU0_SA_DQS_DN<9>
J 0
(2435 3960);
DISPLAY 0.659574 (2435 3960);
PAINT MONO (2435 3960);
DISPLAY INVISIBLE (2435 3960);
FORCEPROP 1 LASTPIN (2425 3950) BN 9
J 0
(2413 3958);
DISPLAY 0.680851 (2413 3958);
PAINT GREEN (2413 3958);
FORCEPROP 2 LAST CDS_LIB standard
J 0
(2475 3950);
DISPLAY INVISIBLE (2475 3950);
FORCEPROP 1 LAST BODY_TYPE PLUMBING
J 0
(2475 4000);
DISPLAY 0.872340 (2475 4000);
PAINT GREEN (2475 4000);
DISPLAY INVISIBLE (2475 4000);
FORCEPROP 1 LAST HDL_TAP TRUE
J 0
(2800 3825);
DISPLAY 0.872340 (2800 3825);
DISPLAY INVISIBLE (2800 3825);
FORCEPROP 1 LAST PATH I147
J 0
(2473 3950);
DISPLAY 0.872340 (2473 3950);
PAINT GREEN (2473 3950);
DISPLAY INVISIBLE (2473 3950);
FORCEADD TAP..1
(2475 3900);
FORCEPROP 3 LASTPIN (2425 3900) SIG_NAME M_H_CPU0_SA_DQS_DN<8>
J 0
(2435 3910);
DISPLAY 0.659574 (2435 3910);
PAINT MONO (2435 3910);
DISPLAY INVISIBLE (2435 3910);
FORCEPROP 1 LASTPIN (2425 3900) BN 8
J 0
(2413 3908);
DISPLAY 0.680851 (2413 3908);
PAINT GREEN (2413 3908);
FORCEPROP 2 LAST CDS_LIB standard
J 0
(2475 3900);
DISPLAY INVISIBLE (2475 3900);
FORCEPROP 1 LAST BODY_TYPE PLUMBING
J 0
(2475 3950);
DISPLAY 0.872340 (2475 3950);
PAINT GREEN (2475 3950);
DISPLAY INVISIBLE (2475 3950);
FORCEPROP 1 LAST HDL_TAP TRUE
J 0
(2800 3775);
DISPLAY 0.872340 (2800 3775);
DISPLAY INVISIBLE (2800 3775);
FORCEPROP 1 LAST PATH I148
J 0
(2473 3900);
DISPLAY 0.872340 (2473 3900);
PAINT GREEN (2473 3900);
DISPLAY INVISIBLE (2473 3900);
FORCEADD TAP..1
(2475 4050);
FORCEPROP 3 LASTPIN (2425 4050) SIG_NAME M_H_CPU0_SA_DQS_DP<0>
J 0
(2435 4060);
DISPLAY 0.659574 (2435 4060);
PAINT MONO (2435 4060);
DISPLAY INVISIBLE (2435 4060);
FORCEPROP 1 LASTPIN (2425 4050) BN 0
J 0
(2413 4058);
DISPLAY 0.680851 (2413 4058);
PAINT GREEN (2413 4058);
FORCEPROP 2 LAST CDS_LIB standard
J 0
(2475 4050);
DISPLAY INVISIBLE (2475 4050);
FORCEPROP 1 LAST BODY_TYPE PLUMBING
J 0
(2475 4100);
DISPLAY 0.872340 (2475 4100);
PAINT GREEN (2475 4100);
DISPLAY INVISIBLE (2475 4100);
FORCEPROP 1 LAST HDL_TAP TRUE
J 0
(2800 3925);
DISPLAY 0.872340 (2800 3925);
DISPLAY INVISIBLE (2800 3925);
FORCEPROP 1 LAST PATH I149
J 0
(2473 4050);
DISPLAY 0.872340 (2473 4050);
PAINT GREEN (2473 4050);
DISPLAY INVISIBLE (2473 4050);
FORCEADD TAP..1
R 2
(-950 800);
FORCEPROP 3 LASTPIN (-900 800) SIG_NAME M_H_CPU0_SB_CB<5>
J 0
(-890 810);
DISPLAY 0.659574 (-890 810);
PAINT MONO (-890 810);
DISPLAY INVISIBLE (-890 810);
FORCEPROP 1 LASTPIN (-900 800) BN 5
J 2
(-888 808);
DISPLAY 0.680851 (-888 808);
PAINT GREEN (-888 808);
FORCEPROP 2 LAST CDS_LIB standard
J 0
(-950 800);
DISPLAY INVISIBLE (-950 800);
FORCEPROP 1 LAST BODY_TYPE PLUMBING
J 2
(-950 850);
DISPLAY 0.872340 (-950 850);
PAINT GREEN (-950 850);
DISPLAY INVISIBLE (-950 850);
FORCEPROP 1 LAST HDL_TAP TRUE
J 2
(-1275 675);
DISPLAY 0.872340 (-1275 675);
DISPLAY INVISIBLE (-1275 675);
FORCEPROP 1 LAST PATH I15
J 2
(-948 800);
DISPLAY 0.872340 (-948 800);
PAINT GREEN (-948 800);
DISPLAY INVISIBLE (-948 800);
FORCEADD TAP..1
(2475 4100);
FORCEPROP 3 LASTPIN (2425 4100) SIG_NAME M_H_CPU0_SA_DQS_DP<1>
J 0
(2435 4110);
DISPLAY 0.659574 (2435 4110);
PAINT MONO (2435 4110);
DISPLAY INVISIBLE (2435 4110);
FORCEPROP 1 LASTPIN (2425 4100) BN 1
J 0
(2413 4108);
DISPLAY 0.680851 (2413 4108);
PAINT GREEN (2413 4108);
FORCEPROP 2 LAST CDS_LIB standard
J 0
(2475 4100);
DISPLAY INVISIBLE (2475 4100);
FORCEPROP 1 LAST BODY_TYPE PLUMBING
J 0
(2475 4150);
DISPLAY 0.872340 (2475 4150);
PAINT GREEN (2475 4150);
DISPLAY INVISIBLE (2475 4150);
FORCEPROP 1 LAST HDL_TAP TRUE
J 0
(2800 3975);
DISPLAY 0.872340 (2800 3975);
DISPLAY INVISIBLE (2800 3975);
FORCEPROP 1 LAST PATH I150
J 0
(2473 4100);
DISPLAY 0.872340 (2473 4100);
PAINT GREEN (2473 4100);
DISPLAY INVISIBLE (2473 4100);
FORCEADD TAP..1
(2475 4200);
FORCEPROP 3 LASTPIN (2425 4200) SIG_NAME M_H_CPU0_SA_DQS_DP<3>
J 0
(2435 4210);
DISPLAY 0.659574 (2435 4210);
PAINT MONO (2435 4210);
DISPLAY INVISIBLE (2435 4210);
FORCEPROP 1 LASTPIN (2425 4200) BN 3
J 0
(2413 4208);
DISPLAY 0.680851 (2413 4208);
PAINT GREEN (2413 4208);
FORCEPROP 2 LAST CDS_LIB standard
J 0
(2475 4200);
DISPLAY INVISIBLE (2475 4200);
FORCEPROP 1 LAST BODY_TYPE PLUMBING
J 0
(2475 4250);
DISPLAY 0.872340 (2475 4250);
PAINT GREEN (2475 4250);
DISPLAY INVISIBLE (2475 4250);
FORCEPROP 1 LAST HDL_TAP TRUE
J 0
(2800 4075);
DISPLAY 0.872340 (2800 4075);
DISPLAY INVISIBLE (2800 4075);
FORCEPROP 1 LAST PATH I151
J 0
(2473 4200);
DISPLAY 0.872340 (2473 4200);
PAINT GREEN (2473 4200);
DISPLAY INVISIBLE (2473 4200);
FORCEADD TAP..1
(2475 4150);
FORCEPROP 3 LASTPIN (2425 4150) SIG_NAME M_H_CPU0_SA_DQS_DP<2>
J 0
(2435 4160);
DISPLAY 0.659574 (2435 4160);
PAINT MONO (2435 4160);
DISPLAY INVISIBLE (2435 4160);
FORCEPROP 1 LASTPIN (2425 4150) BN 2
J 0
(2413 4158);
DISPLAY 0.680851 (2413 4158);
PAINT GREEN (2413 4158);
FORCEPROP 2 LAST CDS_LIB standard
J 0
(2475 4150);
DISPLAY INVISIBLE (2475 4150);
FORCEPROP 1 LAST BODY_TYPE PLUMBING
J 0
(2475 4200);
DISPLAY 0.872340 (2475 4200);
PAINT GREEN (2475 4200);
DISPLAY INVISIBLE (2475 4200);
FORCEPROP 1 LAST HDL_TAP TRUE
J 0
(2800 4025);
DISPLAY 0.872340 (2800 4025);
DISPLAY INVISIBLE (2800 4025);
FORCEPROP 1 LAST PATH I152
J 0
(2473 4150);
DISPLAY 0.872340 (2473 4150);
PAINT GREEN (2473 4150);
DISPLAY INVISIBLE (2473 4150);
FORCEADD TAP..1
(2475 4250);
FORCEPROP 3 LASTPIN (2425 4250) SIG_NAME M_H_CPU0_SA_DQS_DP<4>
J 0
(2435 4260);
DISPLAY 0.659574 (2435 4260);
PAINT MONO (2435 4260);
DISPLAY INVISIBLE (2435 4260);
FORCEPROP 1 LASTPIN (2425 4250) BN 4
J 0
(2413 4258);
DISPLAY 0.680851 (2413 4258);
PAINT GREEN (2413 4258);
FORCEPROP 2 LAST CDS_LIB standard
J 0
(2475 4250);
DISPLAY INVISIBLE (2475 4250);
FORCEPROP 1 LAST BODY_TYPE PLUMBING
J 0
(2475 4300);
DISPLAY 0.872340 (2475 4300);
PAINT GREEN (2475 4300);
DISPLAY INVISIBLE (2475 4300);
FORCEPROP 1 LAST HDL_TAP TRUE
J 0
(2800 4125);
DISPLAY 0.872340 (2800 4125);
DISPLAY INVISIBLE (2800 4125);
FORCEPROP 1 LAST PATH I153
J 0
(2473 4250);
DISPLAY 0.872340 (2473 4250);
PAINT GREEN (2473 4250);
DISPLAY INVISIBLE (2473 4250);
FORCEADD TAP..1
(2475 4300);
FORCEPROP 3 LASTPIN (2425 4300) SIG_NAME M_H_CPU0_SA_DQS_DP<5>
J 0
(2435 4310);
DISPLAY 0.659574 (2435 4310);
PAINT MONO (2435 4310);
DISPLAY INVISIBLE (2435 4310);
FORCEPROP 1 LASTPIN (2425 4300) BN 5
J 0
(2413 4308);
DISPLAY 0.680851 (2413 4308);
PAINT GREEN (2413 4308);
FORCEPROP 2 LAST CDS_LIB standard
J 0
(2475 4300);
DISPLAY INVISIBLE (2475 4300);
FORCEPROP 1 LAST BODY_TYPE PLUMBING
J 0
(2475 4350);
DISPLAY 0.872340 (2475 4350);
PAINT GREEN (2475 4350);
DISPLAY INVISIBLE (2475 4350);
FORCEPROP 1 LAST HDL_TAP TRUE
J 0
(2800 4175);
DISPLAY 0.872340 (2800 4175);
DISPLAY INVISIBLE (2800 4175);
FORCEPROP 1 LAST PATH I154
J 0
(2473 4300);
DISPLAY 0.872340 (2473 4300);
PAINT GREEN (2473 4300);
DISPLAY INVISIBLE (2473 4300);
FORCEADD TAP..1
(2475 4350);
FORCEPROP 3 LASTPIN (2425 4350) SIG_NAME M_H_CPU0_SA_DQS_DP<6>
J 0
(2435 4360);
DISPLAY 0.659574 (2435 4360);
PAINT MONO (2435 4360);
DISPLAY INVISIBLE (2435 4360);
FORCEPROP 1 LASTPIN (2425 4350) BN 6
J 0
(2413 4358);
DISPLAY 0.680851 (2413 4358);
PAINT GREEN (2413 4358);
FORCEPROP 2 LAST CDS_LIB standard
J 0
(2475 4350);
DISPLAY INVISIBLE (2475 4350);
FORCEPROP 1 LAST BODY_TYPE PLUMBING
J 0
(2475 4400);
DISPLAY 0.872340 (2475 4400);
PAINT GREEN (2475 4400);
DISPLAY INVISIBLE (2475 4400);
FORCEPROP 1 LAST HDL_TAP TRUE
J 0
(2800 4225);
DISPLAY 0.872340 (2800 4225);
DISPLAY INVISIBLE (2800 4225);
FORCEPROP 1 LAST PATH I155
J 0
(2473 4350);
DISPLAY 0.872340 (2473 4350);
PAINT GREEN (2473 4350);
DISPLAY INVISIBLE (2473 4350);
FORCEADD TAP..1
(2475 4450);
FORCEPROP 3 LASTPIN (2425 4450) SIG_NAME M_H_CPU0_SA_DQS_DP<8>
J 0
(2435 4460);
DISPLAY 0.659574 (2435 4460);
PAINT MONO (2435 4460);
DISPLAY INVISIBLE (2435 4460);
FORCEPROP 1 LASTPIN (2425 4450) BN 8
J 0
(2413 4458);
DISPLAY 0.680851 (2413 4458);
PAINT GREEN (2413 4458);
FORCEPROP 2 LAST CDS_LIB standard
J 0
(2475 4450);
DISPLAY INVISIBLE (2475 4450);
FORCEPROP 1 LAST BODY_TYPE PLUMBING
J 0
(2475 4500);
DISPLAY 0.872340 (2475 4500);
PAINT GREEN (2475 4500);
DISPLAY INVISIBLE (2475 4500);
FORCEPROP 1 LAST HDL_TAP TRUE
J 0
(2800 4325);
DISPLAY 0.872340 (2800 4325);
DISPLAY INVISIBLE (2800 4325);
FORCEPROP 1 LAST PATH I156
J 0
(2473 4450);
DISPLAY 0.872340 (2473 4450);
PAINT GREEN (2473 4450);
DISPLAY INVISIBLE (2473 4450);
FORCEADD TAP..1
(2475 4400);
FORCEPROP 3 LASTPIN (2425 4400) SIG_NAME M_H_CPU0_SA_DQS_DP<7>
J 0
(2435 4410);
DISPLAY 0.659574 (2435 4410);
PAINT MONO (2435 4410);
DISPLAY INVISIBLE (2435 4410);
FORCEPROP 1 LASTPIN (2425 4400) BN 7
J 0
(2413 4408);
DISPLAY 0.680851 (2413 4408);
PAINT GREEN (2413 4408);
FORCEPROP 2 LAST CDS_LIB standard
J 0
(2475 4400);
DISPLAY INVISIBLE (2475 4400);
FORCEPROP 1 LAST BODY_TYPE PLUMBING
J 0
(2475 4450);
DISPLAY 0.872340 (2475 4450);
PAINT GREEN (2475 4450);
DISPLAY INVISIBLE (2475 4450);
FORCEPROP 1 LAST HDL_TAP TRUE
J 0
(2800 4275);
DISPLAY 0.872340 (2800 4275);
DISPLAY INVISIBLE (2800 4275);
FORCEPROP 1 LAST PATH I157
J 0
(2473 4400);
DISPLAY 0.872340 (2473 4400);
PAINT GREEN (2473 4400);
DISPLAY INVISIBLE (2473 4400);
FORCEADD TAP..1
(2475 4500);
FORCEPROP 3 LASTPIN (2425 4500) SIG_NAME M_H_CPU0_SA_DQS_DP<9>
J 0
(2435 4510);
DISPLAY 0.659574 (2435 4510);
PAINT MONO (2435 4510);
DISPLAY INVISIBLE (2435 4510);
FORCEPROP 1 LASTPIN (2425 4500) BN 9
J 0
(2413 4508);
DISPLAY 0.680851 (2413 4508);
PAINT GREEN (2413 4508);
FORCEPROP 2 LAST CDS_LIB standard
J 0
(2475 4500);
DISPLAY INVISIBLE (2475 4500);
FORCEPROP 1 LAST BODY_TYPE PLUMBING
J 0
(2475 4550);
DISPLAY 0.872340 (2475 4550);
PAINT GREEN (2475 4550);
DISPLAY INVISIBLE (2475 4550);
FORCEPROP 1 LAST HDL_TAP TRUE
J 0
(2800 4375);
DISPLAY 0.872340 (2800 4375);
DISPLAY INVISIBLE (2800 4375);
FORCEPROP 1 LAST PATH I158
J 0
(2473 4500);
DISPLAY 0.872340 (2473 4500);
PAINT GREEN (2473 4500);
DISPLAY INVISIBLE (2473 4500);
FORCEADD OFFPAGE..2
(3575 925);
FORCEPROP 2 LAST $XR1 97 
J 0
(3854 925);
DISPLAY 0.638298 (3854 925);
PAINT MONO (3854 925);
FORCEPROP 2 LAST $XR0 96 
J 0
(3764 925);
DISPLAY 0.638298 (3764 925);
PAINT MONO (3764 925);
FORCEPROP 2 LAST CDS_LIB standard
J 0
(3575 925);
PAINT MONO (3575 925);
DISPLAY INVISIBLE (3575 925);
FORCEPROP 1 LAST OFFPAGE TRUE
J 0
(3900 800);
DISPLAY 1.170213 (3900 800);
PAINT GREEN (3900 800);
DISPLAY INVISIBLE (3900 800);
FORCEPROP 1 LAST COMMENT_BODY TRUE
J 0
(3530 830);
DISPLAY 1.170213 (3530 830);
PAINT GREEN (3530 830);
DISPLAY INVISIBLE (3530 830);
FORCEPROP 2 LAST PATH I159
J 0
(3750 1000);
DISPLAY 1.021277 (3750 1000);
DISPLAY INVISIBLE (3750 1000);
FORCEADD TAP..1
R 2
(-950 950);
FORCEPROP 3 LASTPIN (-900 950) SIG_NAME M_H_CPU0_SB_DQ<0>
J 0
(-890 960);
DISPLAY 0.659574 (-890 960);
PAINT MONO (-890 960);
DISPLAY INVISIBLE (-890 960);
FORCEPROP 1 LASTPIN (-900 950) BN 0
J 2
(-888 958);
DISPLAY 0.680851 (-888 958);
PAINT GREEN (-888 958);
FORCEPROP 2 LAST CDS_LIB standard
J 0
(-950 950);
DISPLAY INVISIBLE (-950 950);
FORCEPROP 1 LAST BODY_TYPE PLUMBING
J 2
(-950 1000);
DISPLAY 0.872340 (-950 1000);
PAINT GREEN (-950 1000);
DISPLAY INVISIBLE (-950 1000);
FORCEPROP 1 LAST HDL_TAP TRUE
J 2
(-1275 825);
DISPLAY 0.872340 (-1275 825);
DISPLAY INVISIBLE (-1275 825);
FORCEPROP 1 LAST PATH I16
J 2
(-948 950);
DISPLAY 0.872340 (-948 950);
PAINT GREEN (-948 950);
DISPLAY INVISIBLE (-948 950);
FORCEADD OFFPAGE..2
(3575 1225);
FORCEPROP 2 LAST $XR1 97 
J 0
(3854 1225);
DISPLAY 0.638298 (3854 1225);
PAINT MONO (3854 1225);
FORCEPROP 2 LAST $XR0 96 
J 0
(3764 1225);
DISPLAY 0.638298 (3764 1225);
PAINT MONO (3764 1225);
FORCEPROP 2 LAST CDS_LIB standard
J 0
(3575 1225);
PAINT MONO (3575 1225);
DISPLAY INVISIBLE (3575 1225);
FORCEPROP 1 LAST OFFPAGE TRUE
J 0
(3900 1100);
DISPLAY 1.170213 (3900 1100);
PAINT GREEN (3900 1100);
DISPLAY INVISIBLE (3900 1100);
FORCEPROP 1 LAST COMMENT_BODY TRUE
J 0
(3530 1130);
DISPLAY 1.170213 (3530 1130);
PAINT GREEN (3530 1130);
DISPLAY INVISIBLE (3530 1130);
FORCEPROP 2 LAST PATH I160
J 0
(3750 1300);
DISPLAY 1.021277 (3750 1300);
DISPLAY INVISIBLE (3750 1300);
FORCEADD OFFPAGE..2
(3575 1350);
FORCEPROP 2 LAST $XR1 97 
J 0
(3854 1350);
DISPLAY 0.638298 (3854 1350);
PAINT MONO (3854 1350);
FORCEPROP 2 LAST $XR0 96 
J 0
(3764 1350);
DISPLAY 0.638298 (3764 1350);
PAINT MONO (3764 1350);
FORCEPROP 2 LAST CDS_LIB standard
J 0
(3575 1350);
PAINT MONO (3575 1350);
DISPLAY INVISIBLE (3575 1350);
FORCEPROP 1 LAST OFFPAGE TRUE
J 0
(3900 1225);
DISPLAY 1.170213 (3900 1225);
PAINT GREEN (3900 1225);
DISPLAY INVISIBLE (3900 1225);
FORCEPROP 1 LAST COMMENT_BODY TRUE
J 0
(3530 1255);
DISPLAY 1.170213 (3530 1255);
PAINT GREEN (3530 1255);
DISPLAY INVISIBLE (3530 1255);
FORCEPROP 2 LAST PATH I161
J 0
(3750 1425);
DISPLAY 1.021277 (3750 1425);
DISPLAY INVISIBLE (3750 1425);
FORCEADD OFFPAGE..3
(3575 1725);
FORCEPROP 2 LAST $XR1 97 
J 0
(3879 1725);
DISPLAY 0.638298 (3879 1725);
PAINT MONO (3879 1725);
FORCEPROP 2 LAST $XR0 96 
J 0
(3789 1725);
DISPLAY 0.638298 (3789 1725);
PAINT MONO (3789 1725);
FORCEPROP 2 LAST CDS_LIB standard
J 2
(3575 1725);
DISPLAY INVISIBLE (3575 1725);
FORCEPROP 1 LAST OFFPAGE TRUE
J 0
(3900 1600);
DISPLAY 0.872340 (3900 1600);
DISPLAY INVISIBLE (3900 1600);
FORCEPROP 1 LAST COMMENT_BODY TRUE
J 0
(3525 1625);
DISPLAY 0.872340 (3525 1625);
PAINT GREEN (3525 1625);
DISPLAY INVISIBLE (3525 1625);
FORCEPROP 2 LAST PATH I162
J 0
(3775 1800);
DISPLAY 1.021277 (3775 1800);
DISPLAY INVISIBLE (3775 1800);
FORCEADD OFFPAGE..2
(3575 1850);
FORCEPROP 2 LAST $XR1 97 
J 0
(3854 1850);
DISPLAY 0.638298 (3854 1850);
PAINT MONO (3854 1850);
FORCEPROP 2 LAST $XR0 96 
J 0
(3764 1850);
DISPLAY 0.638298 (3764 1850);
PAINT MONO (3764 1850);
FORCEPROP 2 LAST CDS_LIB standard
J 0
(3575 1850);
PAINT MONO (3575 1850);
DISPLAY INVISIBLE (3575 1850);
FORCEPROP 1 LAST OFFPAGE TRUE
J 0
(3900 1725);
DISPLAY 1.170213 (3900 1725);
PAINT GREEN (3900 1725);
DISPLAY INVISIBLE (3900 1725);
FORCEPROP 1 LAST COMMENT_BODY TRUE
J 0
(3530 1755);
DISPLAY 1.170213 (3530 1755);
PAINT GREEN (3530 1755);
DISPLAY INVISIBLE (3530 1755);
FORCEPROP 2 LAST PATH I163
J 0
(3750 1925);
DISPLAY 1.021277 (3750 1925);
DISPLAY INVISIBLE (3750 1925);
FORCEADD OFFPAGE..3
(3575 2225);
FORCEPROP 2 LAST $XR1 97 
J 0
(3879 2225);
DISPLAY 0.638298 (3879 2225);
PAINT MONO (3879 2225);
FORCEPROP 2 LAST $XR0 96 
J 0
(3789 2225);
DISPLAY 0.638298 (3789 2225);
PAINT MONO (3789 2225);
FORCEPROP 2 LAST CDS_LIB standard
J 2
(3575 2225);
DISPLAY INVISIBLE (3575 2225);
FORCEPROP 1 LAST OFFPAGE TRUE
J 0
(3900 2100);
DISPLAY 0.872340 (3900 2100);
DISPLAY INVISIBLE (3900 2100);
FORCEPROP 1 LAST COMMENT_BODY TRUE
J 0
(3525 2125);
DISPLAY 0.872340 (3525 2125);
PAINT GREEN (3525 2125);
DISPLAY INVISIBLE (3525 2125);
FORCEPROP 2 LAST PATH I164
J 0
(3775 2300);
DISPLAY 1.021277 (3775 2300);
DISPLAY INVISIBLE (3775 2300);
FORCEADD OFFPAGE..3
(3575 2825);
FORCEPROP 2 LAST $XR1 97 
J 0
(3879 2825);
DISPLAY 0.638298 (3879 2825);
PAINT MONO (3879 2825);
FORCEPROP 2 LAST $XR0 96 
J 0
(3789 2825);
DISPLAY 0.638298 (3789 2825);
PAINT MONO (3789 2825);
FORCEPROP 2 LAST CDS_LIB standard
J 2
(3575 2825);
DISPLAY INVISIBLE (3575 2825);
FORCEPROP 1 LAST OFFPAGE TRUE
J 0
(3900 2700);
DISPLAY 0.872340 (3900 2700);
DISPLAY INVISIBLE (3900 2700);
FORCEPROP 1 LAST COMMENT_BODY TRUE
J 0
(3525 2725);
DISPLAY 0.872340 (3525 2725);
PAINT GREEN (3525 2725);
DISPLAY INVISIBLE (3525 2725);
FORCEPROP 2 LAST PATH I165
J 0
(3775 2900);
DISPLAY 1.021277 (3775 2900);
DISPLAY INVISIBLE (3775 2900);
FORCEADD OFFPAGE..3
(3575 3375);
FORCEPROP 2 LAST $XR1 97 
J 0
(3879 3375);
DISPLAY 0.638298 (3879 3375);
PAINT MONO (3879 3375);
FORCEPROP 2 LAST $XR0 96 
J 0
(3789 3375);
DISPLAY 0.638298 (3789 3375);
PAINT MONO (3789 3375);
FORCEPROP 2 LAST CDS_LIB standard
J 2
(3575 3375);
DISPLAY INVISIBLE (3575 3375);
FORCEPROP 1 LAST OFFPAGE TRUE
J 0
(3900 3250);
DISPLAY 0.872340 (3900 3250);
DISPLAY INVISIBLE (3900 3250);
FORCEPROP 1 LAST COMMENT_BODY TRUE
J 0
(3525 3275);
DISPLAY 0.872340 (3525 3275);
PAINT GREEN (3525 3275);
DISPLAY INVISIBLE (3525 3275);
FORCEPROP 2 LAST PATH I166
J 0
(3775 3450);
DISPLAY 1.021277 (3775 3450);
DISPLAY INVISIBLE (3775 3450);
FORCEADD OFFPAGE..3
(3575 3975);
FORCEPROP 2 LAST $XR1 97 
J 0
(3879 3975);
DISPLAY 0.638298 (3879 3975);
PAINT MONO (3879 3975);
FORCEPROP 2 LAST $XR0 96 
J 0
(3789 3975);
DISPLAY 0.638298 (3789 3975);
PAINT MONO (3789 3975);
FORCEPROP 2 LAST CDS_LIB standard
J 2
(3575 3975);
DISPLAY INVISIBLE (3575 3975);
FORCEPROP 1 LAST OFFPAGE TRUE
J 0
(3900 3850);
DISPLAY 0.872340 (3900 3850);
DISPLAY INVISIBLE (3900 3850);
FORCEPROP 1 LAST COMMENT_BODY TRUE
J 0
(3525 3875);
DISPLAY 0.872340 (3525 3875);
PAINT GREEN (3525 3875);
DISPLAY INVISIBLE (3525 3875);
FORCEPROP 2 LAST PATH I167
J 0
(3775 4050);
DISPLAY 1.021277 (3775 4050);
DISPLAY INVISIBLE (3775 4050);
FORCEADD OFFPAGE..3
(3575 4525);
FORCEPROP 2 LAST $XR1 97 
J 0
(3879 4525);
DISPLAY 0.638298 (3879 4525);
PAINT MONO (3879 4525);
FORCEPROP 2 LAST $XR0 96 
J 0
(3789 4525);
DISPLAY 0.638298 (3789 4525);
PAINT MONO (3789 4525);
FORCEPROP 2 LAST CDS_LIB standard
J 2
(3575 4525);
DISPLAY INVISIBLE (3575 4525);
FORCEPROP 1 LAST OFFPAGE TRUE
J 0
(3900 4400);
DISPLAY 0.872340 (3900 4400);
DISPLAY INVISIBLE (3900 4400);
FORCEPROP 1 LAST COMMENT_BODY TRUE
J 0
(3525 4425);
DISPLAY 0.872340 (3525 4425);
PAINT GREEN (3525 4425);
DISPLAY INVISIBLE (3525 4425);
FORCEPROP 2 LAST PATH I168
J 0
(3775 4600);
DISPLAY 1.021277 (3775 4600);
DISPLAY INVISIBLE (3775 4600);
FORCEADD SOCKET4677_AZIF0045P001C01CS..15
(775 2400);
FORCEPROP 1 LAST PART_NUMBER DGA^7000023
J 0
(-325 4750);
DISPLAY 0.723404 (-325 4750);
PAINT GREEN (-325 4750);
DISPLAY INVISIBLE (-325 4750);
FORCEPROP 2 LAST PART_TYPE SMLF
J 0
(-325 4925);
DISPLAY 1.021277 (-325 4925);
FORCEPROP 1 LAST MATERIAL IO
J 0
(-325 4675);
DISPLAY 0.723404 (-325 4675);
PAINT GREEN (-325 4675);
FORCEPROP 2 LAST VALUE SOCKET4677_AZIF0045-P001C01CS
J 0
(-325 4875);
DISPLAY 1.021277 (-325 4875);
FORCEPROP 1 LAST $LOCATION U2
J 0
(-325 4825);
DISPLAY 0.723404 (-325 4825);
PAINT GREEN (-325 4825);
FORCEPROP 0 LASTPIN (2000 550) $PN EG48
J 0
(2010 560);
DISPLAY 0.680851 (2010 560);
PAINT MONO (2010 560);
FORCEPROP 0 LASTPIN (2000 600) $PN EH47
J 0
(2010 610);
DISPLAY 0.680851 (2010 610);
PAINT MONO (2010 610);
FORCEPROP 0 LASTPIN (2000 300) $PN CY51
J 0
(2010 310);
DISPLAY 0.680851 (2010 310);
PAINT MONO (2010 310);
FORCEPROP 0 LASTPIN (2000 400) $PN EE48
J 0
(2010 410);
DISPLAY 0.680851 (2010 410);
PAINT MONO (2010 410);
FORCEPROP 0 LASTPIN (2000 450) $PN ED47
J 0
(2010 460);
DISPLAY 0.680851 (2010 460);
PAINT MONO (2010 460);
FORCEPROP 0 LASTPIN (-450 300) $PN DH42
J 2
(-460 310);
DISPLAY 0.680851 (-460 310);
PAINT MONO (-460 310);
FORCEPROP 0 LASTPIN (-450 350) $PN DD42
J 2
(-460 360);
DISPLAY 0.680851 (-460 360);
PAINT MONO (-460 360);
FORCEPROP 0 LASTPIN (-450 400) $PN DF42
J 2
(-460 410);
DISPLAY 0.680851 (-460 410);
PAINT MONO (-460 410);
FORCEPROP 0 LASTPIN (-450 450) $PN DB42
J 2
(-460 460);
DISPLAY 0.680851 (-460 460);
PAINT MONO (-460 460);
FORCEPROP 0 LASTPIN (2000 1900) $PN DB49
J 0
(2010 1910);
DISPLAY 0.680851 (2010 1910);
PAINT MONO (2010 1910);
FORCEPROP 0 LASTPIN (2000 1950) $PN DH49
J 0
(2010 1960);
DISPLAY 0.680851 (2010 1960);
PAINT MONO (2010 1960);
FORCEPROP 0 LASTPIN (2000 2000) $PN DC48
J 0
(2010 2010);
DISPLAY 0.680851 (2010 2010);
PAINT MONO (2010 2010);
FORCEPROP 0 LASTPIN (2000 2050) $PN DG48
J 0
(2010 2060);
DISPLAY 0.680851 (2010 2060);
PAINT MONO (2010 2060);
FORCEPROP 0 LASTPIN (2000 2100) $PN DD47
J 0
(2010 2110);
DISPLAY 0.680851 (2010 2110);
PAINT MONO (2010 2110);
FORCEPROP 0 LASTPIN (2000 2150) $PN DF47
J 0
(2010 2160);
DISPLAY 0.680851 (2010 2160);
PAINT MONO (2010 2160);
FORCEPROP 0 LASTPIN (2000 2200) $PN DC41
J 0
(2010 2210);
DISPLAY 0.680851 (2010 2210);
PAINT MONO (2010 2210);
FORCEPROP 0 LASTPIN (-450 2950) $PN DY79
J 2
(-460 2960);
DISPLAY 0.680851 (-460 2960);
PAINT MONO (-460 2960);
FORCEPROP 0 LASTPIN (-450 3000) $PN DT77
J 2
(-460 3010);
DISPLAY 0.680851 (-460 3010);
PAINT MONO (-460 3010);
FORCEPROP 0 LASTPIN (-450 3050) $PN DW78
J 2
(-460 3060);
DISPLAY 0.680851 (-460 3060);
PAINT MONO (-460 3060);
FORCEPROP 0 LASTPIN (-450 3100) $PN DP77
J 2
(-460 3110);
DISPLAY 0.680851 (-460 3110);
PAINT MONO (-460 3110);
FORCEPROP 0 LASTPIN (-450 3150) $PN DK75
J 2
(-460 3160);
DISPLAY 0.680851 (-460 3160);
PAINT MONO (-460 3160);
FORCEPROP 0 LASTPIN (-450 3200) $PN DL74
J 2
(-460 3210);
DISPLAY 0.680851 (-460 3210);
PAINT MONO (-460 3210);
FORCEPROP 0 LASTPIN (-450 3250) $PN DP75
J 2
(-460 3260);
DISPLAY 0.680851 (-460 3260);
PAINT MONO (-460 3260);
FORCEPROP 0 LASTPIN (-450 3300) $PN DN74
J 2
(-460 3310);
DISPLAY 0.680851 (-460 3310);
PAINT MONO (-460 3310);
FORCEPROP 0 LASTPIN (-450 3350) $PN DD75
J 2
(-460 3360);
DISPLAY 0.680851 (-460 3360);
PAINT MONO (-460 3360);
FORCEPROP 0 LASTPIN (-450 3400) $PN DC74
J 2
(-460 3410);
DISPLAY 0.680851 (-460 3410);
PAINT MONO (-460 3410);
FORCEPROP 0 LASTPIN (-450 3450) $PN DF75
J 2
(-460 3460);
DISPLAY 0.680851 (-460 3460);
PAINT MONO (-460 3460);
FORCEPROP 0 LASTPIN (-450 3500) $PN DG74
J 2
(-460 3510);
DISPLAY 0.680851 (-460 3510);
PAINT MONO (-460 3510);
FORCEPROP 0 LASTPIN (-450 3550) $PN DC72
J 2
(-460 3560);
DISPLAY 0.680851 (-460 3560);
PAINT MONO (-460 3560);
FORCEPROP 0 LASTPIN (-450 3600) $PN DD71
J 2
(-460 3610);
DISPLAY 0.680851 (-460 3610);
PAINT MONO (-460 3610);
FORCEPROP 0 LASTPIN (-450 3650) $PN DG72
J 2
(-460 3660);
DISPLAY 0.680851 (-460 3660);
PAINT MONO (-460 3660);
FORCEPROP 0 LASTPIN (-450 3700) $PN DF71
J 2
(-460 3710);
DISPLAY 0.680851 (-460 3710);
PAINT MONO (-460 3710);
FORCEPROP 0 LASTPIN (-450 3750) $PN DD69
J 2
(-460 3760);
DISPLAY 0.680851 (-460 3760);
PAINT MONO (-460 3760);
FORCEPROP 0 LASTPIN (-450 3800) $PN DC68
J 2
(-460 3810);
DISPLAY 0.680851 (-460 3810);
PAINT MONO (-460 3810);
FORCEPROP 0 LASTPIN (-450 3850) $PN DF69
J 2
(-460 3860);
DISPLAY 0.680851 (-460 3860);
PAINT MONO (-460 3860);
FORCEPROP 0 LASTPIN (-450 3900) $PN DG68
J 2
(-460 3910);
DISPLAY 0.680851 (-460 3910);
PAINT MONO (-460 3910);
FORCEPROP 0 LASTPIN (-450 3950) $PN DC66
J 2
(-460 3960);
DISPLAY 0.680851 (-460 3960);
PAINT MONO (-460 3960);
FORCEPROP 0 LASTPIN (-450 4000) $PN DD65
J 2
(-460 4010);
DISPLAY 0.680851 (-460 4010);
PAINT MONO (-460 4010);
FORCEPROP 0 LASTPIN (-450 4050) $PN DG66
J 2
(-460 4060);
DISPLAY 0.680851 (-460 4060);
PAINT MONO (-460 4060);
FORCEPROP 0 LASTPIN (-450 4100) $PN DF65
J 2
(-460 4110);
DISPLAY 0.680851 (-460 4110);
PAINT MONO (-460 4110);
FORCEPROP 0 LASTPIN (-450 4150) $PN DD63
J 2
(-460 4160);
DISPLAY 0.680851 (-460 4160);
PAINT MONO (-460 4160);
FORCEPROP 0 LASTPIN (-450 4200) $PN DC62
J 2
(-460 4210);
DISPLAY 0.680851 (-460 4210);
PAINT MONO (-460 4210);
FORCEPROP 0 LASTPIN (-450 4250) $PN DF63
J 2
(-460 4260);
DISPLAY 0.680851 (-460 4260);
PAINT MONO (-460 4260);
FORCEPROP 0 LASTPIN (-450 4300) $PN DG62
J 2
(-460 4310);
DISPLAY 0.680851 (-460 4310);
PAINT MONO (-460 4310);
FORCEPROP 0 LASTPIN (-450 4350) $PN DC60
J 2
(-460 4360);
DISPLAY 0.680851 (-460 4360);
PAINT MONO (-460 4360);
FORCEPROP 0 LASTPIN (-450 4400) $PN DD59
J 2
(-460 4410);
DISPLAY 0.680851 (-460 4410);
PAINT MONO (-460 4410);
FORCEPROP 0 LASTPIN (-450 4450) $PN DG60
J 2
(-460 4460);
DISPLAY 0.680851 (-460 4460);
PAINT MONO (-460 4460);
FORCEPROP 0 LASTPIN (-450 4500) $PN DF59
J 2
(-460 4510);
DISPLAY 0.680851 (-460 4510);
PAINT MONO (-460 4510);
FORCEPROP 0 LASTPIN (2000 3500) $PN DJ76
J 0
(2010 3510);
DISPLAY 0.680851 (2010 3510);
PAINT MONO (2010 3510);
FORCEPROP 0 LASTPIN (2000 3550) $PN DB73
J 0
(2010 3560);
DISPLAY 0.680851 (2010 3560);
PAINT MONO (2010 3560);
FORCEPROP 0 LASTPIN (2000 3600) $PN DD67
J 0
(2010 3610);
DISPLAY 0.680851 (2010 3610);
PAINT MONO (2010 3610);
FORCEPROP 0 LASTPIN (2000 3650) $PN DD61
J 0
(2010 3660);
DISPLAY 0.680851 (2010 3660);
PAINT MONO (2010 3660);
FORCEPROP 0 LASTPIN (2000 3700) $PN DD55
J 0
(2010 3710);
DISPLAY 0.680851 (2010 3710);
PAINT MONO (2010 3710);
FORCEPROP 0 LASTPIN (2000 3750) $PN DR76
J 0
(2010 3760);
DISPLAY 0.680851 (2010 3760);
PAINT MONO (2010 3760);
FORCEPROP 0 LASTPIN (2000 3800) $PN DH73
J 0
(2010 3810);
DISPLAY 0.680851 (2010 3810);
PAINT MONO (2010 3810);
FORCEPROP 0 LASTPIN (2000 3850) $PN DH67
J 0
(2010 3860);
DISPLAY 0.680851 (2010 3860);
PAINT MONO (2010 3860);
FORCEPROP 0 LASTPIN (2000 3900) $PN DH61
J 0
(2010 3910);
DISPLAY 0.680851 (2010 3910);
PAINT MONO (2010 3910);
FORCEPROP 0 LASTPIN (2000 3950) $PN DH55
J 0
(2010 3960);
DISPLAY 0.680851 (2010 3960);
PAINT MONO (2010 3960);
FORCEPROP 0 LASTPIN (2000 4050) $PN DL76
J 0
(2010 4060);
DISPLAY 0.680851 (2010 4060);
PAINT MONO (2010 4060);
FORCEPROP 0 LASTPIN (2000 4100) $PN DD73
J 0
(2010 4110);
DISPLAY 0.680851 (2010 4110);
PAINT MONO (2010 4110);
FORCEPROP 0 LASTPIN (2000 4150) $PN DB67
J 0
(2010 4160);
DISPLAY 0.680851 (2010 4160);
PAINT MONO (2010 4160);
FORCEPROP 0 LASTPIN (2000 4200) $PN DB61
J 0
(2010 4210);
DISPLAY 0.680851 (2010 4210);
PAINT MONO (2010 4210);
FORCEPROP 0 LASTPIN (2000 4250) $PN DB55
J 0
(2010 4260);
DISPLAY 0.680851 (2010 4260);
PAINT MONO (2010 4260);
FORCEPROP 0 LASTPIN (2000 4300) $PN DN76
J 0
(2010 4310);
DISPLAY 0.680851 (2010 4310);
PAINT MONO (2010 4310);
FORCEPROP 0 LASTPIN (2000 4350) $PN DF73
J 0
(2010 4360);
DISPLAY 0.680851 (2010 4360);
PAINT MONO (2010 4360);
FORCEPROP 0 LASTPIN (2000 4400) $PN DF67
J 0
(2010 4410);
DISPLAY 0.680851 (2010 4410);
PAINT MONO (2010 4410);
FORCEPROP 0 LASTPIN (2000 4450) $PN DF61
J 0
(2010 4460);
DISPLAY 0.680851 (2010 4460);
PAINT MONO (2010 4460);
FORCEPROP 0 LASTPIN (2000 4500) $PN DF55
J 0
(2010 4510);
DISPLAY 0.680851 (2010 4510);
PAINT MONO (2010 4510);
FORCEPROP 0 LASTPIN (-450 2550) $PN DD57
J 2
(-460 2560);
DISPLAY 0.680851 (-460 2560);
PAINT MONO (-460 2560);
FORCEPROP 0 LASTPIN (-450 2600) $PN DC56
J 2
(-460 2610);
DISPLAY 0.680851 (-460 2610);
PAINT MONO (-460 2610);
FORCEPROP 0 LASTPIN (-450 2650) $PN DF57
J 2
(-460 2660);
DISPLAY 0.680851 (-460 2660);
PAINT MONO (-460 2660);
FORCEPROP 0 LASTPIN (-450 2700) $PN DG56
J 2
(-460 2710);
DISPLAY 0.680851 (-460 2710);
PAINT MONO (-460 2710);
FORCEPROP 0 LASTPIN (-450 2750) $PN DC54
J 2
(-460 2760);
DISPLAY 0.680851 (-460 2760);
PAINT MONO (-460 2760);
FORCEPROP 0 LASTPIN (-450 2800) $PN DD53
J 2
(-460 2810);
DISPLAY 0.680851 (-460 2810);
PAINT MONO (-460 2810);
FORCEPROP 0 LASTPIN (-450 2850) $PN DG54
J 2
(-460 2860);
DISPLAY 0.680851 (-460 2860);
PAINT MONO (-460 2860);
FORCEPROP 0 LASTPIN (-450 2900) $PN DF53
J 2
(-460 2910);
DISPLAY 0.680851 (-460 2910);
PAINT MONO (-460 2910);
FORCEPROP 0 LASTPIN (2000 1850) $PN DD40
J 0
(2010 1860);
DISPLAY 0.680851 (2010 1860);
PAINT MONO (2010 1860);
FORCEPROP 0 LASTPIN (2000 1400) $PN DF40
J 0
(2010 1410);
DISPLAY 0.680851 (2010 1410);
PAINT MONO (2010 1410);
FORCEPROP 0 LASTPIN (2000 1450) $PN DG41
J 0
(2010 1460);
DISPLAY 0.680851 (2010 1460);
PAINT MONO (2010 1460);
FORCEPROP 0 LASTPIN (2000 1500) $PN DL41
J 0
(2010 1510);
DISPLAY 0.680851 (2010 1510);
PAINT MONO (2010 1510);
FORCEPROP 0 LASTPIN (2000 1550) $PN DN41
J 0
(2010 1560);
DISPLAY 0.680851 (2010 1560);
PAINT MONO (2010 1560);
FORCEPROP 0 LASTPIN (2000 1600) $PN DK40
J 0
(2010 1610);
DISPLAY 0.680851 (2010 1610);
PAINT MONO (2010 1610);
FORCEPROP 0 LASTPIN (2000 1650) $PN DP40
J 0
(2010 1660);
DISPLAY 0.680851 (2010 1660);
PAINT MONO (2010 1660);
FORCEPROP 0 LASTPIN (2000 1700) $PN DJ39
J 0
(2010 1710);
DISPLAY 0.680851 (2010 1710);
PAINT MONO (2010 1710);
FORCEPROP 0 LASTPIN (-450 950) $PN DD32
J 2
(-460 960);
DISPLAY 0.680851 (-460 960);
PAINT MONO (-460 960);
FORCEPROP 0 LASTPIN (-450 1000) $PN DC31
J 2
(-460 1010);
DISPLAY 0.680851 (-460 1010);
PAINT MONO (-460 1010);
FORCEPROP 0 LASTPIN (-450 1050) $PN DF32
J 2
(-460 1060);
DISPLAY 0.680851 (-460 1060);
PAINT MONO (-460 1060);
FORCEPROP 0 LASTPIN (-450 1100) $PN DG31
J 2
(-460 1110);
DISPLAY 0.680851 (-460 1110);
PAINT MONO (-460 1110);
FORCEPROP 0 LASTPIN (-450 1150) $PN DC29
J 2
(-460 1160);
DISPLAY 0.680851 (-460 1160);
PAINT MONO (-460 1160);
FORCEPROP 0 LASTPIN (-450 1200) $PN DF28
J 2
(-460 1210);
DISPLAY 0.680851 (-460 1210);
PAINT MONO (-460 1210);
FORCEPROP 0 LASTPIN (-450 1250) $PN DG29
J 2
(-460 1260);
DISPLAY 0.680851 (-460 1260);
PAINT MONO (-460 1260);
FORCEPROP 0 LASTPIN (-450 1300) $PN DD28
J 2
(-460 1310);
DISPLAY 0.680851 (-460 1310);
PAINT MONO (-460 1310);
FORCEPROP 0 LASTPIN (-450 1350) $PN DD26
J 2
(-460 1360);
DISPLAY 0.680851 (-460 1360);
PAINT MONO (-460 1360);
FORCEPROP 0 LASTPIN (-450 1400) $PN DC25
J 2
(-460 1410);
DISPLAY 0.680851 (-460 1410);
PAINT MONO (-460 1410);
FORCEPROP 0 LASTPIN (-450 1450) $PN DF26
J 2
(-460 1460);
DISPLAY 0.680851 (-460 1460);
PAINT MONO (-460 1460);
FORCEPROP 0 LASTPIN (-450 1500) $PN DG25
J 2
(-460 1510);
DISPLAY 0.680851 (-460 1510);
PAINT MONO (-460 1510);
FORCEPROP 0 LASTPIN (-450 1550) $PN DC23
J 2
(-460 1560);
DISPLAY 0.680851 (-460 1560);
PAINT MONO (-460 1560);
FORCEPROP 0 LASTPIN (-450 1600) $PN DD22
J 2
(-460 1610);
DISPLAY 0.680851 (-460 1610);
PAINT MONO (-460 1610);
FORCEPROP 0 LASTPIN (-450 1650) $PN DG23
J 2
(-460 1660);
DISPLAY 0.680851 (-460 1660);
PAINT MONO (-460 1660);
FORCEPROP 0 LASTPIN (-450 1700) $PN DF22
J 2
(-460 1710);
DISPLAY 0.680851 (-460 1710);
PAINT MONO (-460 1710);
FORCEPROP 0 LASTPIN (-450 1750) $PN DL23
J 2
(-460 1760);
DISPLAY 0.680851 (-460 1760);
PAINT MONO (-460 1760);
FORCEPROP 0 LASTPIN (-450 1800) $PN DK22
J 2
(-460 1810);
DISPLAY 0.680851 (-460 1810);
PAINT MONO (-460 1810);
FORCEPROP 0 LASTPIN (-450 1850) $PN DN23
J 2
(-460 1860);
DISPLAY 0.680851 (-460 1860);
PAINT MONO (-460 1860);
FORCEPROP 0 LASTPIN (-450 1900) $PN DP22
J 2
(-460 1910);
DISPLAY 0.680851 (-460 1910);
PAINT MONO (-460 1910);
FORCEPROP 0 LASTPIN (-450 1950) $PN DK20
J 2
(-460 1960);
DISPLAY 0.680851 (-460 1960);
PAINT MONO (-460 1960);
FORCEPROP 0 LASTPIN (-450 2000) $PN DL19
J 2
(-460 2010);
DISPLAY 0.680851 (-460 2010);
PAINT MONO (-460 2010);
FORCEPROP 0 LASTPIN (-450 2050) $PN DP20
J 2
(-460 2060);
DISPLAY 0.680851 (-460 2060);
PAINT MONO (-460 2060);
FORCEPROP 0 LASTPIN (-450 2100) $PN DN19
J 2
(-460 2110);
DISPLAY 0.680851 (-460 2110);
PAINT MONO (-460 2110);
FORCEPROP 0 LASTPIN (-450 2150) $PN DD20
J 2
(-460 2160);
DISPLAY 0.680851 (-460 2160);
PAINT MONO (-460 2160);
FORCEPROP 0 LASTPIN (-450 2200) $PN DC19
J 2
(-460 2210);
DISPLAY 0.680851 (-460 2210);
PAINT MONO (-460 2210);
FORCEPROP 0 LASTPIN (-450 2250) $PN DF20
J 2
(-460 2260);
DISPLAY 0.680851 (-460 2260);
PAINT MONO (-460 2260);
FORCEPROP 0 LASTPIN (-450 2300) $PN DG19
J 2
(-460 2310);
DISPLAY 0.680851 (-460 2310);
PAINT MONO (-460 2310);
FORCEPROP 0 LASTPIN (-450 2350) $PN DG17
J 2
(-460 2360);
DISPLAY 0.680851 (-460 2360);
PAINT MONO (-460 2360);
FORCEPROP 0 LASTPIN (-450 2400) $PN DA17
J 2
(-460 2410);
DISPLAY 0.680851 (-460 2410);
PAINT MONO (-460 2410);
FORCEPROP 0 LASTPIN (-450 2450) $PN DJ17
J 2
(-460 2460);
DISPLAY 0.680851 (-460 2460);
PAINT MONO (-460 2460);
FORCEPROP 0 LASTPIN (-450 2500) $PN DC17
J 2
(-460 2510);
DISPLAY 0.680851 (-460 2510);
PAINT MONO (-460 2510);
FORCEPROP 0 LASTPIN (2000 2350) $PN DD30
J 0
(2010 2360);
DISPLAY 0.680851 (2010 2360);
PAINT MONO (2010 2360);
FORCEPROP 0 LASTPIN (2000 2400) $PN DD24
J 0
(2010 2410);
DISPLAY 0.680851 (2010 2410);
PAINT MONO (2010 2410);
FORCEPROP 0 LASTPIN (2000 2450) $PN DL21
J 0
(2010 2460);
DISPLAY 0.680851 (2010 2460);
PAINT MONO (2010 2460);
FORCEPROP 0 LASTPIN (2000 2500) $PN DB18
J 0
(2010 2510);
DISPLAY 0.680851 (2010 2510);
PAINT MONO (2010 2510);
FORCEPROP 0 LASTPIN (2000 2550) $PN DH36
J 0
(2010 2560);
DISPLAY 0.680851 (2010 2560);
PAINT MONO (2010 2560);
FORCEPROP 0 LASTPIN (2000 2600) $PN DH30
J 0
(2010 2610);
DISPLAY 0.680851 (2010 2610);
PAINT MONO (2010 2610);
FORCEPROP 0 LASTPIN (2000 2650) $PN DH24
J 0
(2010 2660);
DISPLAY 0.680851 (2010 2660);
PAINT MONO (2010 2660);
FORCEPROP 0 LASTPIN (2000 2700) $PN DR21
J 0
(2010 2710);
DISPLAY 0.680851 (2010 2710);
PAINT MONO (2010 2710);
FORCEPROP 0 LASTPIN (2000 2750) $PN DF18
J 0
(2010 2760);
DISPLAY 0.680851 (2010 2760);
PAINT MONO (2010 2760);
FORCEPROP 0 LASTPIN (2000 2800) $PN DD36
J 0
(2010 2810);
DISPLAY 0.680851 (2010 2810);
PAINT MONO (2010 2810);
FORCEPROP 0 LASTPIN (2000 2900) $PN DB30
J 0
(2010 2910);
DISPLAY 0.680851 (2010 2910);
PAINT MONO (2010 2910);
FORCEPROP 0 LASTPIN (2000 2950) $PN DB24
J 0
(2010 2960);
DISPLAY 0.680851 (2010 2960);
PAINT MONO (2010 2960);
FORCEPROP 0 LASTPIN (2000 3000) $PN DJ21
J 0
(2010 3010);
DISPLAY 0.680851 (2010 3010);
PAINT MONO (2010 3010);
FORCEPROP 0 LASTPIN (2000 3050) $PN DD18
J 0
(2010 3060);
DISPLAY 0.680851 (2010 3060);
PAINT MONO (2010 3060);
FORCEPROP 0 LASTPIN (2000 3100) $PN DF36
J 0
(2010 3110);
DISPLAY 0.680851 (2010 3110);
PAINT MONO (2010 3110);
FORCEPROP 0 LASTPIN (2000 3150) $PN DF30
J 0
(2010 3160);
DISPLAY 0.680851 (2010 3160);
PAINT MONO (2010 3160);
FORCEPROP 0 LASTPIN (2000 3200) $PN DF24
J 0
(2010 3210);
DISPLAY 0.680851 (2010 3210);
PAINT MONO (2010 3210);
FORCEPROP 0 LASTPIN (2000 3250) $PN DN21
J 0
(2010 3260);
DISPLAY 0.680851 (2010 3260);
PAINT MONO (2010 3260);
FORCEPROP 0 LASTPIN (2000 3300) $PN DH18
J 0
(2010 3310);
DISPLAY 0.680851 (2010 3310);
PAINT MONO (2010 3310);
FORCEPROP 0 LASTPIN (2000 3350) $PN DB36
J 0
(2010 3360);
DISPLAY 0.680851 (2010 3360);
PAINT MONO (2010 3360);
FORCEPROP 0 LASTPIN (-450 550) $PN DC35
J 2
(-460 560);
DISPLAY 0.680851 (-460 560);
PAINT MONO (-460 560);
FORCEPROP 0 LASTPIN (-450 600) $PN DD34
J 2
(-460 610);
DISPLAY 0.680851 (-460 610);
PAINT MONO (-460 610);
FORCEPROP 0 LASTPIN (-450 650) $PN DG35
J 2
(-460 660);
DISPLAY 0.680851 (-460 660);
PAINT MONO (-460 660);
FORCEPROP 0 LASTPIN (-450 700) $PN DF34
J 2
(-460 710);
DISPLAY 0.680851 (-460 710);
PAINT MONO (-460 710);
FORCEPROP 0 LASTPIN (-450 750) $PN DF38
J 2
(-460 760);
DISPLAY 0.680851 (-460 760);
PAINT MONO (-460 760);
FORCEPROP 0 LASTPIN (-450 800) $PN DG37
J 2
(-460 810);
DISPLAY 0.680851 (-460 810);
PAINT MONO (-460 810);
FORCEPROP 0 LASTPIN (-450 850) $PN DD38
J 2
(-460 860);
DISPLAY 0.680851 (-460 860);
PAINT MONO (-460 860);
FORCEPROP 0 LASTPIN (-450 900) $PN DC37
J 2
(-460 910);
DISPLAY 0.680851 (-460 910);
PAINT MONO (-460 910);
FORCEPROP 0 LASTPIN (2000 1350) $PN DR39
J 0
(2010 1360);
DISPLAY 0.680851 (2010 1360);
PAINT MONO (2010 1360);
FORCEPROP 0 LASTPIN (2000 1050) $PN DF51
J 0
(2010 1060);
DISPLAY 0.680851 (2010 1060);
PAINT MONO (2010 1060);
FORCEPROP 0 LASTPIN (2000 1100) $PN DG50
J 0
(2010 1110);
DISPLAY 0.680851 (2010 1110);
PAINT MONO (2010 1110);
FORCEPROP 0 LASTPIN (2000 1150) $PN DD51
J 0
(2010 1160);
DISPLAY 0.680851 (2010 1160);
PAINT MONO (2010 1160);
FORCEPROP 0 LASTPIN (2000 1200) $PN DC50
J 0
(2010 1210);
DISPLAY 0.680851 (2010 1210);
PAINT MONO (2010 1210);
FORCEPROP 0 LASTPIN (2000 750) $PN DL37
J 0
(2010 760);
DISPLAY 0.680851 (2010 760);
PAINT MONO (2010 760);
FORCEPROP 0 LASTPIN (2000 800) $PN DN37
J 0
(2010 810);
DISPLAY 0.680851 (2010 810);
PAINT MONO (2010 810);
FORCEPROP 0 LASTPIN (2000 850) $PN DK38
J 0
(2010 860);
DISPLAY 0.680851 (2010 860);
PAINT MONO (2010 860);
FORCEPROP 0 LASTPIN (2000 900) $PN DP38
J 0
(2010 910);
DISPLAY 0.680851 (2010 910);
PAINT MONO (2010 910);
FORCEPROP 2 LAST CDS_LIB pure_quanta
J 0
(775 2400);
DISPLAY INVISIBLE (775 2400);
FORCEPROP 1 LAST NEEDS_NO_SIZE TRUE
J 0
(775 2400);
DISPLAY 0.723404 (775 2400);
PAINT GREEN (775 2400);
DISPLAY INVISIBLE (775 2400);
FORCEPROP 1 LAST CDS_LMAN_SYM_OUTLINE -1100,2250,1050,-2250
J 0
(775 2400);
DISPLAY 0.468085 (775 2400);
PAINT GREEN (775 2400);
DISPLAY INVISIBLE (775 2400);
FORCEPROP 2 LAST CDS_LOCATION U2
J 0
(-325 4975);
DISPLAY 1.021277 (-325 4975);
DISPLAY INVISIBLE (-325 4975);
FORCEPROP 0 LAST $SEC 15
J 0
(-325 4975);
DISPLAY 0.680851 (-325 4975);
PAINT MONO (-325 4975);
DISPLAY INVISIBLE (-325 4975);
FORCEPROP 2 LAST CDS_SEC 15
J 0
(-325 4975);
DISPLAY 1.021277 (-325 4975);
DISPLAY INVISIBLE (-325 4975);
FORCEPROP 1 LAST PATH I169
J 0
(775 2400);
DISPLAY 0.723404 (775 2400);
PAINT GREEN (775 2400);
DISPLAY INVISIBLE (775 2400);
FORCEADD TAP..1
R 2
(-950 900);
FORCEPROP 3 LASTPIN (-900 900) SIG_NAME M_H_CPU0_SB_CB<7>
J 0
(-890 910);
DISPLAY 0.659574 (-890 910);
PAINT MONO (-890 910);
DISPLAY INVISIBLE (-890 910);
FORCEPROP 1 LASTPIN (-900 900) BN 7
J 2
(-888 908);
DISPLAY 0.680851 (-888 908);
PAINT GREEN (-888 908);
FORCEPROP 2 LAST CDS_LIB standard
J 0
(-950 900);
DISPLAY INVISIBLE (-950 900);
FORCEPROP 1 LAST BODY_TYPE PLUMBING
J 2
(-950 950);
DISPLAY 0.872340 (-950 950);
PAINT GREEN (-950 950);
DISPLAY INVISIBLE (-950 950);
FORCEPROP 1 LAST HDL_TAP TRUE
J 2
(-1275 775);
DISPLAY 0.872340 (-1275 775);
DISPLAY INVISIBLE (-1275 775);
FORCEPROP 1 LAST PATH I17
J 2
(-948 900);
DISPLAY 0.872340 (-948 900);
PAINT GREEN (-948 900);
DISPLAY INVISIBLE (-948 900);
FORCEADD TAP..1
R 2
(-950 1000);
FORCEPROP 3 LASTPIN (-900 1000) SIG_NAME M_H_CPU0_SB_DQ<1>
J 0
(-890 1010);
DISPLAY 0.659574 (-890 1010);
PAINT MONO (-890 1010);
DISPLAY INVISIBLE (-890 1010);
FORCEPROP 1 LASTPIN (-900 1000) BN 1
J 2
(-888 1008);
DISPLAY 0.680851 (-888 1008);
PAINT GREEN (-888 1008);
FORCEPROP 2 LAST CDS_LIB standard
J 0
(-950 1000);
DISPLAY INVISIBLE (-950 1000);
FORCEPROP 1 LAST BODY_TYPE PLUMBING
J 2
(-950 1050);
DISPLAY 0.872340 (-950 1050);
PAINT GREEN (-950 1050);
DISPLAY INVISIBLE (-950 1050);
FORCEPROP 1 LAST HDL_TAP TRUE
J 2
(-1275 875);
DISPLAY 0.872340 (-1275 875);
DISPLAY INVISIBLE (-1275 875);
FORCEPROP 1 LAST PATH I18
J 2
(-948 1000);
DISPLAY 0.872340 (-948 1000);
PAINT GREEN (-948 1000);
DISPLAY INVISIBLE (-948 1000);
FORCEADD TAP..1
R 2
(-950 1100);
FORCEPROP 3 LASTPIN (-900 1100) SIG_NAME M_H_CPU0_SB_DQ<3>
J 0
(-890 1110);
DISPLAY 0.659574 (-890 1110);
PAINT MONO (-890 1110);
DISPLAY INVISIBLE (-890 1110);
FORCEPROP 1 LASTPIN (-900 1100) BN 3
J 2
(-888 1108);
DISPLAY 0.680851 (-888 1108);
PAINT GREEN (-888 1108);
FORCEPROP 2 LAST CDS_LIB standard
J 0
(-950 1100);
DISPLAY INVISIBLE (-950 1100);
FORCEPROP 1 LAST BODY_TYPE PLUMBING
J 2
(-950 1150);
DISPLAY 0.872340 (-950 1150);
PAINT GREEN (-950 1150);
DISPLAY INVISIBLE (-950 1150);
FORCEPROP 1 LAST HDL_TAP TRUE
J 2
(-1275 975);
DISPLAY 0.872340 (-1275 975);
DISPLAY INVISIBLE (-1275 975);
FORCEPROP 1 LAST PATH I19
J 2
(-948 1100);
DISPLAY 0.872340 (-948 1100);
PAINT GREEN (-948 1100);
DISPLAY INVISIBLE (-948 1100);
FORCEADD OFFPAGE..2
R 2
(-1975 375);
FORCEPROP 2 LAST $XR1 97 
J 0
(-2319 375);
DISPLAY 0.638298 (-2319 375);
PAINT MONO (-2319 375);
FORCEPROP 2 LAST $XR0 96 
J 0
(-2229 375);
DISPLAY 0.638298 (-2229 375);
PAINT MONO (-2229 375);
FORCEPROP 2 LAST CDS_LIB standard
J 0
(-1975 375);
PAINT MONO (-1975 375);
DISPLAY INVISIBLE (-1975 375);
FORCEPROP 1 LAST OFFPAGE TRUE
J 2
(-2300 250);
DISPLAY 0.872340 (-2300 250);
DISPLAY INVISIBLE (-2300 250);
FORCEPROP 1 LAST COMMENT_BODY TRUE
J 2
(-1930 280);
DISPLAY 0.872340 (-1930 280);
PAINT GREEN (-1930 280);
DISPLAY INVISIBLE (-1930 280);
FORCEPROP 2 LAST PATH I2
J 0
(-1925 450);
DISPLAY 1.021277 (-1925 450);
DISPLAY INVISIBLE (-1925 450);
FORCEADD TAP..1
R 2
(-950 1050);
FORCEPROP 3 LASTPIN (-900 1050) SIG_NAME M_H_CPU0_SB_DQ<2>
J 0
(-890 1060);
DISPLAY 0.659574 (-890 1060);
PAINT MONO (-890 1060);
DISPLAY INVISIBLE (-890 1060);
FORCEPROP 1 LASTPIN (-900 1050) BN 2
J 2
(-888 1058);
DISPLAY 0.680851 (-888 1058);
PAINT GREEN (-888 1058);
FORCEPROP 2 LAST CDS_LIB standard
J 0
(-950 1050);
DISPLAY INVISIBLE (-950 1050);
FORCEPROP 1 LAST BODY_TYPE PLUMBING
J 2
(-950 1100);
DISPLAY 0.872340 (-950 1100);
PAINT GREEN (-950 1100);
DISPLAY INVISIBLE (-950 1100);
FORCEPROP 1 LAST HDL_TAP TRUE
J 2
(-1275 925);
DISPLAY 0.872340 (-1275 925);
DISPLAY INVISIBLE (-1275 925);
FORCEPROP 1 LAST PATH I20
J 2
(-948 1050);
DISPLAY 0.872340 (-948 1050);
PAINT GREEN (-948 1050);
DISPLAY INVISIBLE (-948 1050);
FORCEADD TAP..1
R 2
(-950 1150);
FORCEPROP 3 LASTPIN (-900 1150) SIG_NAME M_H_CPU0_SB_DQ<4>
J 0
(-890 1160);
DISPLAY 0.659574 (-890 1160);
PAINT MONO (-890 1160);
DISPLAY INVISIBLE (-890 1160);
FORCEPROP 1 LASTPIN (-900 1150) BN 4
J 2
(-888 1158);
DISPLAY 0.680851 (-888 1158);
PAINT GREEN (-888 1158);
FORCEPROP 2 LAST CDS_LIB standard
J 0
(-950 1150);
DISPLAY INVISIBLE (-950 1150);
FORCEPROP 1 LAST BODY_TYPE PLUMBING
J 2
(-950 1200);
DISPLAY 0.872340 (-950 1200);
PAINT GREEN (-950 1200);
DISPLAY INVISIBLE (-950 1200);
FORCEPROP 1 LAST HDL_TAP TRUE
J 2
(-1275 1025);
DISPLAY 0.872340 (-1275 1025);
DISPLAY INVISIBLE (-1275 1025);
FORCEPROP 1 LAST PATH I21
J 2
(-948 1150);
DISPLAY 0.872340 (-948 1150);
PAINT GREEN (-948 1150);
DISPLAY INVISIBLE (-948 1150);
FORCEADD TAP..1
R 2
(-950 1250);
FORCEPROP 3 LASTPIN (-900 1250) SIG_NAME M_H_CPU0_SB_DQ<6>
J 0
(-890 1260);
DISPLAY 0.659574 (-890 1260);
PAINT MONO (-890 1260);
DISPLAY INVISIBLE (-890 1260);
FORCEPROP 1 LASTPIN (-900 1250) BN 6
J 2
(-888 1258);
DISPLAY 0.680851 (-888 1258);
PAINT GREEN (-888 1258);
FORCEPROP 2 LAST CDS_LIB standard
J 0
(-950 1250);
DISPLAY INVISIBLE (-950 1250);
FORCEPROP 1 LAST BODY_TYPE PLUMBING
J 2
(-950 1300);
DISPLAY 0.872340 (-950 1300);
PAINT GREEN (-950 1300);
DISPLAY INVISIBLE (-950 1300);
FORCEPROP 1 LAST HDL_TAP TRUE
J 2
(-1275 1125);
DISPLAY 0.872340 (-1275 1125);
DISPLAY INVISIBLE (-1275 1125);
FORCEPROP 1 LAST PATH I22
J 2
(-948 1250);
DISPLAY 0.872340 (-948 1250);
PAINT GREEN (-948 1250);
DISPLAY INVISIBLE (-948 1250);
FORCEADD TAP..1
R 2
(-950 1200);
FORCEPROP 3 LASTPIN (-900 1200) SIG_NAME M_H_CPU0_SB_DQ<5>
J 0
(-890 1210);
DISPLAY 0.659574 (-890 1210);
PAINT MONO (-890 1210);
DISPLAY INVISIBLE (-890 1210);
FORCEPROP 1 LASTPIN (-900 1200) BN 5
J 2
(-888 1208);
DISPLAY 0.680851 (-888 1208);
PAINT GREEN (-888 1208);
FORCEPROP 2 LAST CDS_LIB standard
J 0
(-950 1200);
DISPLAY INVISIBLE (-950 1200);
FORCEPROP 1 LAST BODY_TYPE PLUMBING
J 2
(-950 1250);
DISPLAY 0.872340 (-950 1250);
PAINT GREEN (-950 1250);
DISPLAY INVISIBLE (-950 1250);
FORCEPROP 1 LAST HDL_TAP TRUE
J 2
(-1275 1075);
DISPLAY 0.872340 (-1275 1075);
DISPLAY INVISIBLE (-1275 1075);
FORCEPROP 1 LAST PATH I23
J 2
(-948 1200);
DISPLAY 0.872340 (-948 1200);
PAINT GREEN (-948 1200);
DISPLAY INVISIBLE (-948 1200);
FORCEADD TAP..1
R 2
(-950 1350);
FORCEPROP 3 LASTPIN (-900 1350) SIG_NAME M_H_CPU0_SB_DQ<8>
J 0
(-890 1360);
DISPLAY 0.659574 (-890 1360);
PAINT MONO (-890 1360);
DISPLAY INVISIBLE (-890 1360);
FORCEPROP 1 LASTPIN (-900 1350) BN 8
J 2
(-888 1358);
DISPLAY 0.680851 (-888 1358);
PAINT GREEN (-888 1358);
FORCEPROP 2 LAST CDS_LIB standard
J 0
(-950 1350);
DISPLAY INVISIBLE (-950 1350);
FORCEPROP 1 LAST BODY_TYPE PLUMBING
J 2
(-950 1400);
DISPLAY 0.872340 (-950 1400);
PAINT GREEN (-950 1400);
DISPLAY INVISIBLE (-950 1400);
FORCEPROP 1 LAST HDL_TAP TRUE
J 2
(-1275 1225);
DISPLAY 0.872340 (-1275 1225);
DISPLAY INVISIBLE (-1275 1225);
FORCEPROP 1 LAST PATH I24
J 2
(-948 1350);
DISPLAY 0.872340 (-948 1350);
PAINT GREEN (-948 1350);
DISPLAY INVISIBLE (-948 1350);
FORCEADD TAP..1
R 2
(-950 1300);
FORCEPROP 3 LASTPIN (-900 1300) SIG_NAME M_H_CPU0_SB_DQ<7>
J 0
(-890 1310);
DISPLAY 0.659574 (-890 1310);
PAINT MONO (-890 1310);
DISPLAY INVISIBLE (-890 1310);
FORCEPROP 1 LASTPIN (-900 1300) BN 7
J 2
(-888 1308);
DISPLAY 0.680851 (-888 1308);
PAINT GREEN (-888 1308);
FORCEPROP 2 LAST CDS_LIB standard
J 0
(-950 1300);
DISPLAY INVISIBLE (-950 1300);
FORCEPROP 1 LAST BODY_TYPE PLUMBING
J 2
(-950 1350);
DISPLAY 0.872340 (-950 1350);
PAINT GREEN (-950 1350);
DISPLAY INVISIBLE (-950 1350);
FORCEPROP 1 LAST HDL_TAP TRUE
J 2
(-1275 1175);
DISPLAY 0.872340 (-1275 1175);
DISPLAY INVISIBLE (-1275 1175);
FORCEPROP 1 LAST PATH I25
J 2
(-948 1300);
DISPLAY 0.872340 (-948 1300);
PAINT GREEN (-948 1300);
DISPLAY INVISIBLE (-948 1300);
FORCEADD TAP..1
R 2
(-950 1400);
FORCEPROP 3 LASTPIN (-900 1400) SIG_NAME M_H_CPU0_SB_DQ<9>
J 0
(-890 1410);
DISPLAY 0.659574 (-890 1410);
PAINT MONO (-890 1410);
DISPLAY INVISIBLE (-890 1410);
FORCEPROP 1 LASTPIN (-900 1400) BN 9
J 2
(-888 1408);
DISPLAY 0.680851 (-888 1408);
PAINT GREEN (-888 1408);
FORCEPROP 2 LAST CDS_LIB standard
J 0
(-950 1400);
DISPLAY INVISIBLE (-950 1400);
FORCEPROP 1 LAST BODY_TYPE PLUMBING
J 2
(-950 1450);
DISPLAY 0.872340 (-950 1450);
PAINT GREEN (-950 1450);
DISPLAY INVISIBLE (-950 1450);
FORCEPROP 1 LAST HDL_TAP TRUE
J 2
(-1275 1275);
DISPLAY 0.872340 (-1275 1275);
DISPLAY INVISIBLE (-1275 1275);
FORCEPROP 1 LAST PATH I26
J 2
(-948 1400);
DISPLAY 0.872340 (-948 1400);
PAINT GREEN (-948 1400);
DISPLAY INVISIBLE (-948 1400);
FORCEADD TAP..1
R 2
(-950 1450);
FORCEPROP 3 LASTPIN (-900 1450) SIG_NAME M_H_CPU0_SB_DQ<10>
J 0
(-890 1460);
DISPLAY 0.659574 (-890 1460);
PAINT MONO (-890 1460);
DISPLAY INVISIBLE (-890 1460);
FORCEPROP 1 LASTPIN (-900 1450) BN 10
J 2
(-888 1458);
DISPLAY 0.680851 (-888 1458);
PAINT GREEN (-888 1458);
FORCEPROP 2 LAST CDS_LIB standard
J 0
(-950 1450);
DISPLAY INVISIBLE (-950 1450);
FORCEPROP 1 LAST BODY_TYPE PLUMBING
J 2
(-950 1500);
DISPLAY 0.872340 (-950 1500);
PAINT GREEN (-950 1500);
DISPLAY INVISIBLE (-950 1500);
FORCEPROP 1 LAST HDL_TAP TRUE
J 2
(-1275 1325);
DISPLAY 0.872340 (-1275 1325);
DISPLAY INVISIBLE (-1275 1325);
FORCEPROP 1 LAST PATH I27
J 2
(-948 1450);
DISPLAY 0.872340 (-948 1450);
PAINT GREEN (-948 1450);
DISPLAY INVISIBLE (-948 1450);
FORCEADD TAP..1
R 2
(-950 1500);
FORCEPROP 3 LASTPIN (-900 1500) SIG_NAME M_H_CPU0_SB_DQ<11>
J 0
(-890 1510);
DISPLAY 0.659574 (-890 1510);
PAINT MONO (-890 1510);
DISPLAY INVISIBLE (-890 1510);
FORCEPROP 1 LASTPIN (-900 1500) BN 11
J 2
(-888 1508);
DISPLAY 0.680851 (-888 1508);
PAINT GREEN (-888 1508);
FORCEPROP 2 LAST CDS_LIB standard
J 0
(-950 1500);
DISPLAY INVISIBLE (-950 1500);
FORCEPROP 1 LAST BODY_TYPE PLUMBING
J 2
(-950 1550);
DISPLAY 0.872340 (-950 1550);
PAINT GREEN (-950 1550);
DISPLAY INVISIBLE (-950 1550);
FORCEPROP 1 LAST HDL_TAP TRUE
J 2
(-1275 1375);
DISPLAY 0.872340 (-1275 1375);
DISPLAY INVISIBLE (-1275 1375);
FORCEPROP 1 LAST PATH I28
J 2
(-948 1500);
DISPLAY 0.872340 (-948 1500);
PAINT GREEN (-948 1500);
DISPLAY INVISIBLE (-948 1500);
FORCEADD TAP..1
R 2
(-950 1600);
FORCEPROP 3 LASTPIN (-900 1600) SIG_NAME M_H_CPU0_SB_DQ<13>
J 0
(-890 1610);
DISPLAY 0.659574 (-890 1610);
PAINT MONO (-890 1610);
DISPLAY INVISIBLE (-890 1610);
FORCEPROP 1 LASTPIN (-900 1600) BN 13
J 2
(-888 1608);
DISPLAY 0.680851 (-888 1608);
PAINT GREEN (-888 1608);
FORCEPROP 2 LAST CDS_LIB standard
J 0
(-950 1600);
DISPLAY INVISIBLE (-950 1600);
FORCEPROP 1 LAST BODY_TYPE PLUMBING
J 2
(-950 1650);
DISPLAY 0.872340 (-950 1650);
PAINT GREEN (-950 1650);
DISPLAY INVISIBLE (-950 1650);
FORCEPROP 1 LAST HDL_TAP TRUE
J 2
(-1275 1475);
DISPLAY 0.872340 (-1275 1475);
DISPLAY INVISIBLE (-1275 1475);
FORCEPROP 1 LAST PATH I29
J 2
(-948 1600);
DISPLAY 0.872340 (-948 1600);
PAINT GREEN (-948 1600);
DISPLAY INVISIBLE (-948 1600);
FORCEADD TAP..1
R 2
(-950 350);
FORCEPROP 3 LASTPIN (-900 350) SIG_NAME M_H_CPU0_CLK_DN<1>
J 0
(-890 360);
DISPLAY 0.659574 (-890 360);
PAINT MONO (-890 360);
DISPLAY INVISIBLE (-890 360);
FORCEPROP 1 LASTPIN (-900 350) BN 1
J 2
(-888 358);
DISPLAY 0.680851 (-888 358);
PAINT GREEN (-888 358);
FORCEPROP 2 LAST CDS_LIB standard
J 0
(-950 350);
DISPLAY INVISIBLE (-950 350);
FORCEPROP 1 LAST BODY_TYPE PLUMBING
J 2
(-950 400);
DISPLAY 0.872340 (-950 400);
PAINT GREEN (-950 400);
DISPLAY INVISIBLE (-950 400);
FORCEPROP 1 LAST HDL_TAP TRUE
J 2
(-1275 225);
DISPLAY 0.872340 (-1275 225);
DISPLAY INVISIBLE (-1275 225);
FORCEPROP 1 LAST PATH I3
J 2
(-948 350);
DISPLAY 0.872340 (-948 350);
PAINT GREEN (-948 350);
DISPLAY INVISIBLE (-948 350);
FORCEADD TAP..1
R 2
(-950 1550);
FORCEPROP 3 LASTPIN (-900 1550) SIG_NAME M_H_CPU0_SB_DQ<12>
J 0
(-890 1560);
DISPLAY 0.659574 (-890 1560);
PAINT MONO (-890 1560);
DISPLAY INVISIBLE (-890 1560);
FORCEPROP 1 LASTPIN (-900 1550) BN 12
J 2
(-888 1558);
DISPLAY 0.680851 (-888 1558);
PAINT GREEN (-888 1558);
FORCEPROP 2 LAST CDS_LIB standard
J 0
(-950 1550);
DISPLAY INVISIBLE (-950 1550);
FORCEPROP 1 LAST BODY_TYPE PLUMBING
J 2
(-950 1600);
DISPLAY 0.872340 (-950 1600);
PAINT GREEN (-950 1600);
DISPLAY INVISIBLE (-950 1600);
FORCEPROP 1 LAST HDL_TAP TRUE
J 2
(-1275 1425);
DISPLAY 0.872340 (-1275 1425);
DISPLAY INVISIBLE (-1275 1425);
FORCEPROP 1 LAST PATH I30
J 2
(-948 1550);
DISPLAY 0.872340 (-948 1550);
PAINT GREEN (-948 1550);
DISPLAY INVISIBLE (-948 1550);
FORCEADD TAP..1
R 2
(-950 1650);
FORCEPROP 3 LASTPIN (-900 1650) SIG_NAME M_H_CPU0_SB_DQ<14>
J 0
(-890 1660);
DISPLAY 0.659574 (-890 1660);
PAINT MONO (-890 1660);
DISPLAY INVISIBLE (-890 1660);
FORCEPROP 1 LASTPIN (-900 1650) BN 14
J 2
(-888 1658);
DISPLAY 0.680851 (-888 1658);
PAINT GREEN (-888 1658);
FORCEPROP 2 LAST CDS_LIB standard
J 0
(-950 1650);
DISPLAY INVISIBLE (-950 1650);
FORCEPROP 1 LAST BODY_TYPE PLUMBING
J 2
(-950 1700);
DISPLAY 0.872340 (-950 1700);
PAINT GREEN (-950 1700);
DISPLAY INVISIBLE (-950 1700);
FORCEPROP 1 LAST HDL_TAP TRUE
J 2
(-1275 1525);
DISPLAY 0.872340 (-1275 1525);
DISPLAY INVISIBLE (-1275 1525);
FORCEPROP 1 LAST PATH I31
J 2
(-948 1650);
DISPLAY 0.872340 (-948 1650);
PAINT GREEN (-948 1650);
DISPLAY INVISIBLE (-948 1650);
FORCEADD TAP..1
R 2
(-950 1700);
FORCEPROP 3 LASTPIN (-900 1700) SIG_NAME M_H_CPU0_SB_DQ<15>
J 0
(-890 1710);
DISPLAY 0.659574 (-890 1710);
PAINT MONO (-890 1710);
DISPLAY INVISIBLE (-890 1710);
FORCEPROP 1 LASTPIN (-900 1700) BN 15
J 2
(-888 1708);
DISPLAY 0.680851 (-888 1708);
PAINT GREEN (-888 1708);
FORCEPROP 2 LAST CDS_LIB standard
J 0
(-950 1700);
DISPLAY INVISIBLE (-950 1700);
FORCEPROP 1 LAST BODY_TYPE PLUMBING
J 2
(-950 1750);
DISPLAY 0.872340 (-950 1750);
PAINT GREEN (-950 1750);
DISPLAY INVISIBLE (-950 1750);
FORCEPROP 1 LAST HDL_TAP TRUE
J 2
(-1275 1575);
DISPLAY 0.872340 (-1275 1575);
DISPLAY INVISIBLE (-1275 1575);
FORCEPROP 1 LAST PATH I32
J 2
(-948 1700);
DISPLAY 0.872340 (-948 1700);
PAINT GREEN (-948 1700);
DISPLAY INVISIBLE (-948 1700);
FORCEADD TAP..1
R 2
(-950 1750);
FORCEPROP 3 LASTPIN (-900 1750) SIG_NAME M_H_CPU0_SB_DQ<16>
J 0
(-890 1760);
DISPLAY 0.659574 (-890 1760);
PAINT MONO (-890 1760);
DISPLAY INVISIBLE (-890 1760);
FORCEPROP 1 LASTPIN (-900 1750) BN 16
J 2
(-888 1758);
DISPLAY 0.680851 (-888 1758);
PAINT GREEN (-888 1758);
FORCEPROP 2 LAST CDS_LIB standard
J 0
(-950 1750);
DISPLAY INVISIBLE (-950 1750);
FORCEPROP 1 LAST BODY_TYPE PLUMBING
J 2
(-950 1800);
DISPLAY 0.872340 (-950 1800);
PAINT GREEN (-950 1800);
DISPLAY INVISIBLE (-950 1800);
FORCEPROP 1 LAST HDL_TAP TRUE
J 2
(-1275 1625);
DISPLAY 0.872340 (-1275 1625);
DISPLAY INVISIBLE (-1275 1625);
FORCEPROP 1 LAST PATH I33
J 2
(-948 1750);
DISPLAY 0.872340 (-948 1750);
PAINT GREEN (-948 1750);
DISPLAY INVISIBLE (-948 1750);
FORCEADD TAP..1
R 2
(-950 1850);
FORCEPROP 3 LASTPIN (-900 1850) SIG_NAME M_H_CPU0_SB_DQ<18>
J 0
(-890 1860);
DISPLAY 0.659574 (-890 1860);
PAINT MONO (-890 1860);
DISPLAY INVISIBLE (-890 1860);
FORCEPROP 1 LASTPIN (-900 1850) BN 18
J 2
(-888 1858);
DISPLAY 0.680851 (-888 1858);
PAINT GREEN (-888 1858);
FORCEPROP 2 LAST CDS_LIB standard
J 0
(-950 1850);
DISPLAY INVISIBLE (-950 1850);
FORCEPROP 1 LAST BODY_TYPE PLUMBING
J 2
(-950 1900);
DISPLAY 0.872340 (-950 1900);
PAINT GREEN (-950 1900);
DISPLAY INVISIBLE (-950 1900);
FORCEPROP 1 LAST HDL_TAP TRUE
J 2
(-1275 1725);
DISPLAY 0.872340 (-1275 1725);
DISPLAY INVISIBLE (-1275 1725);
FORCEPROP 1 LAST PATH I34
J 2
(-948 1850);
DISPLAY 0.872340 (-948 1850);
PAINT GREEN (-948 1850);
DISPLAY INVISIBLE (-948 1850);
FORCEADD TAP..1
R 2
(-950 1900);
FORCEPROP 3 LASTPIN (-900 1900) SIG_NAME M_H_CPU0_SB_DQ<19>
J 0
(-890 1910);
DISPLAY 0.659574 (-890 1910);
PAINT MONO (-890 1910);
DISPLAY INVISIBLE (-890 1910);
FORCEPROP 1 LASTPIN (-900 1900) BN 19
J 2
(-888 1908);
DISPLAY 0.680851 (-888 1908);
PAINT GREEN (-888 1908);
FORCEPROP 2 LAST CDS_LIB standard
J 0
(-950 1900);
DISPLAY INVISIBLE (-950 1900);
FORCEPROP 1 LAST BODY_TYPE PLUMBING
J 2
(-950 1950);
DISPLAY 0.872340 (-950 1950);
PAINT GREEN (-950 1950);
DISPLAY INVISIBLE (-950 1950);
FORCEPROP 1 LAST HDL_TAP TRUE
J 2
(-1275 1775);
DISPLAY 0.872340 (-1275 1775);
DISPLAY INVISIBLE (-1275 1775);
FORCEPROP 1 LAST PATH I35
J 2
(-948 1900);
DISPLAY 0.872340 (-948 1900);
PAINT GREEN (-948 1900);
DISPLAY INVISIBLE (-948 1900);
FORCEADD TAP..1
R 2
(-950 1800);
FORCEPROP 3 LASTPIN (-900 1800) SIG_NAME M_H_CPU0_SB_DQ<17>
J 0
(-890 1810);
DISPLAY 0.659574 (-890 1810);
PAINT MONO (-890 1810);
DISPLAY INVISIBLE (-890 1810);
FORCEPROP 1 LASTPIN (-900 1800) BN 17
J 2
(-888 1808);
DISPLAY 0.680851 (-888 1808);
PAINT GREEN (-888 1808);
FORCEPROP 2 LAST CDS_LIB standard
J 0
(-950 1800);
DISPLAY INVISIBLE (-950 1800);
FORCEPROP 1 LAST BODY_TYPE PLUMBING
J 2
(-950 1850);
DISPLAY 0.872340 (-950 1850);
PAINT GREEN (-950 1850);
DISPLAY INVISIBLE (-950 1850);
FORCEPROP 1 LAST HDL_TAP TRUE
J 2
(-1275 1675);
DISPLAY 0.872340 (-1275 1675);
DISPLAY INVISIBLE (-1275 1675);
FORCEPROP 1 LAST PATH I36
J 2
(-948 1800);
DISPLAY 0.872340 (-948 1800);
PAINT GREEN (-948 1800);
DISPLAY INVISIBLE (-948 1800);
FORCEADD TAP..1
R 2
(-950 2000);
FORCEPROP 3 LASTPIN (-900 2000) SIG_NAME M_H_CPU0_SB_DQ<21>
J 0
(-890 2010);
DISPLAY 0.659574 (-890 2010);
PAINT MONO (-890 2010);
DISPLAY INVISIBLE (-890 2010);
FORCEPROP 1 LASTPIN (-900 2000) BN 21
J 2
(-888 2008);
DISPLAY 0.680851 (-888 2008);
PAINT GREEN (-888 2008);
FORCEPROP 2 LAST CDS_LIB standard
J 0
(-950 2000);
DISPLAY INVISIBLE (-950 2000);
FORCEPROP 1 LAST BODY_TYPE PLUMBING
J 2
(-950 2050);
DISPLAY 0.872340 (-950 2050);
PAINT GREEN (-950 2050);
DISPLAY INVISIBLE (-950 2050);
FORCEPROP 1 LAST HDL_TAP TRUE
J 2
(-1275 1875);
DISPLAY 0.872340 (-1275 1875);
DISPLAY INVISIBLE (-1275 1875);
FORCEPROP 1 LAST PATH I37
J 2
(-948 2000);
DISPLAY 0.872340 (-948 2000);
PAINT GREEN (-948 2000);
DISPLAY INVISIBLE (-948 2000);
FORCEADD TAP..1
R 2
(-950 1950);
FORCEPROP 3 LASTPIN (-900 1950) SIG_NAME M_H_CPU0_SB_DQ<20>
J 0
(-890 1960);
DISPLAY 0.659574 (-890 1960);
PAINT MONO (-890 1960);
DISPLAY INVISIBLE (-890 1960);
FORCEPROP 1 LASTPIN (-900 1950) BN 20
J 2
(-888 1958);
DISPLAY 0.680851 (-888 1958);
PAINT GREEN (-888 1958);
FORCEPROP 2 LAST CDS_LIB standard
J 0
(-950 1950);
DISPLAY INVISIBLE (-950 1950);
FORCEPROP 1 LAST BODY_TYPE PLUMBING
J 2
(-950 2000);
DISPLAY 0.872340 (-950 2000);
PAINT GREEN (-950 2000);
DISPLAY INVISIBLE (-950 2000);
FORCEPROP 1 LAST HDL_TAP TRUE
J 2
(-1275 1825);
DISPLAY 0.872340 (-1275 1825);
DISPLAY INVISIBLE (-1275 1825);
FORCEPROP 1 LAST PATH I38
J 2
(-948 1950);
DISPLAY 0.872340 (-948 1950);
PAINT GREEN (-948 1950);
DISPLAY INVISIBLE (-948 1950);
FORCEADD TAP..1
R 2
(-950 2050);
FORCEPROP 3 LASTPIN (-900 2050) SIG_NAME M_H_CPU0_SB_DQ<22>
J 0
(-890 2060);
DISPLAY 0.659574 (-890 2060);
PAINT MONO (-890 2060);
DISPLAY INVISIBLE (-890 2060);
FORCEPROP 1 LASTPIN (-900 2050) BN 22
J 2
(-888 2058);
DISPLAY 0.680851 (-888 2058);
PAINT GREEN (-888 2058);
FORCEPROP 2 LAST CDS_LIB standard
J 0
(-950 2050);
DISPLAY INVISIBLE (-950 2050);
FORCEPROP 1 LAST BODY_TYPE PLUMBING
J 2
(-950 2100);
DISPLAY 0.872340 (-950 2100);
PAINT GREEN (-950 2100);
DISPLAY INVISIBLE (-950 2100);
FORCEPROP 1 LAST HDL_TAP TRUE
J 2
(-1275 1925);
DISPLAY 0.872340 (-1275 1925);
DISPLAY INVISIBLE (-1275 1925);
FORCEPROP 1 LAST PATH I39
J 2
(-948 2050);
DISPLAY 0.872340 (-948 2050);
PAINT GREEN (-948 2050);
DISPLAY INVISIBLE (-948 2050);
FORCEADD TAP..1
R 2
(-950 300);
FORCEPROP 3 LASTPIN (-900 300) SIG_NAME M_H_CPU0_CLK_DN<0>
J 0
(-890 310);
DISPLAY 0.659574 (-890 310);
PAINT MONO (-890 310);
DISPLAY INVISIBLE (-890 310);
FORCEPROP 1 LASTPIN (-900 300) BN 0
J 2
(-888 308);
DISPLAY 0.680851 (-888 308);
PAINT GREEN (-888 308);
FORCEPROP 2 LAST CDS_LIB standard
J 0
(-950 300);
DISPLAY INVISIBLE (-950 300);
FORCEPROP 1 LAST BODY_TYPE PLUMBING
J 2
(-950 350);
DISPLAY 0.872340 (-950 350);
PAINT GREEN (-950 350);
DISPLAY INVISIBLE (-950 350);
FORCEPROP 1 LAST HDL_TAP TRUE
J 2
(-1275 175);
DISPLAY 0.872340 (-1275 175);
DISPLAY INVISIBLE (-1275 175);
FORCEPROP 1 LAST PATH I4
J 2
(-948 300);
DISPLAY 0.872340 (-948 300);
PAINT GREEN (-948 300);
DISPLAY INVISIBLE (-948 300);
FORCEADD TAP..1
R 2
(-950 2100);
FORCEPROP 3 LASTPIN (-900 2100) SIG_NAME M_H_CPU0_SB_DQ<23>
J 0
(-890 2110);
DISPLAY 0.659574 (-890 2110);
PAINT MONO (-890 2110);
DISPLAY INVISIBLE (-890 2110);
FORCEPROP 1 LASTPIN (-900 2100) BN 23
J 2
(-888 2108);
DISPLAY 0.680851 (-888 2108);
PAINT GREEN (-888 2108);
FORCEPROP 2 LAST CDS_LIB standard
J 0
(-950 2100);
DISPLAY INVISIBLE (-950 2100);
FORCEPROP 1 LAST BODY_TYPE PLUMBING
J 2
(-950 2150);
DISPLAY 0.872340 (-950 2150);
PAINT GREEN (-950 2150);
DISPLAY INVISIBLE (-950 2150);
FORCEPROP 1 LAST HDL_TAP TRUE
J 2
(-1275 1975);
DISPLAY 0.872340 (-1275 1975);
DISPLAY INVISIBLE (-1275 1975);
FORCEPROP 1 LAST PATH I40
J 2
(-948 2100);
DISPLAY 0.872340 (-948 2100);
PAINT GREEN (-948 2100);
DISPLAY INVISIBLE (-948 2100);
FORCEADD TAP..1
R 2
(-950 2150);
FORCEPROP 3 LASTPIN (-900 2150) SIG_NAME M_H_CPU0_SB_DQ<24>
J 0
(-890 2160);
DISPLAY 0.659574 (-890 2160);
PAINT MONO (-890 2160);
DISPLAY INVISIBLE (-890 2160);
FORCEPROP 1 LASTPIN (-900 2150) BN 24
J 2
(-888 2158);
DISPLAY 0.680851 (-888 2158);
PAINT GREEN (-888 2158);
FORCEPROP 2 LAST CDS_LIB standard
J 0
(-950 2150);
DISPLAY INVISIBLE (-950 2150);
FORCEPROP 1 LAST BODY_TYPE PLUMBING
J 2
(-950 2200);
DISPLAY 0.872340 (-950 2200);
PAINT GREEN (-950 2200);
DISPLAY INVISIBLE (-950 2200);
FORCEPROP 1 LAST HDL_TAP TRUE
J 2
(-1275 2025);
DISPLAY 0.872340 (-1275 2025);
DISPLAY INVISIBLE (-1275 2025);
FORCEPROP 1 LAST PATH I41
J 2
(-948 2150);
DISPLAY 0.872340 (-948 2150);
PAINT GREEN (-948 2150);
DISPLAY INVISIBLE (-948 2150);
FORCEADD TAP..1
R 2
(-950 2200);
FORCEPROP 3 LASTPIN (-900 2200) SIG_NAME M_H_CPU0_SB_DQ<25>
J 0
(-890 2210);
DISPLAY 0.659574 (-890 2210);
PAINT MONO (-890 2210);
DISPLAY INVISIBLE (-890 2210);
FORCEPROP 1 LASTPIN (-900 2200) BN 25
J 2
(-888 2208);
DISPLAY 0.680851 (-888 2208);
PAINT GREEN (-888 2208);
FORCEPROP 2 LAST CDS_LIB standard
J 0
(-950 2200);
DISPLAY INVISIBLE (-950 2200);
FORCEPROP 1 LAST BODY_TYPE PLUMBING
J 2
(-950 2250);
DISPLAY 0.872340 (-950 2250);
PAINT GREEN (-950 2250);
DISPLAY INVISIBLE (-950 2250);
FORCEPROP 1 LAST HDL_TAP TRUE
J 2
(-1275 2075);
DISPLAY 0.872340 (-1275 2075);
DISPLAY INVISIBLE (-1275 2075);
FORCEPROP 1 LAST PATH I42
J 2
(-948 2200);
DISPLAY 0.872340 (-948 2200);
PAINT GREEN (-948 2200);
DISPLAY INVISIBLE (-948 2200);
FORCEADD TAP..1
R 2
(-950 2250);
FORCEPROP 3 LASTPIN (-900 2250) SIG_NAME M_H_CPU0_SB_DQ<26>
J 0
(-890 2260);
DISPLAY 0.659574 (-890 2260);
PAINT MONO (-890 2260);
DISPLAY INVISIBLE (-890 2260);
FORCEPROP 1 LASTPIN (-900 2250) BN 26
J 2
(-888 2258);
DISPLAY 0.680851 (-888 2258);
PAINT GREEN (-888 2258);
FORCEPROP 2 LAST CDS_LIB standard
J 0
(-950 2250);
DISPLAY INVISIBLE (-950 2250);
FORCEPROP 1 LAST BODY_TYPE PLUMBING
J 2
(-950 2300);
DISPLAY 0.872340 (-950 2300);
PAINT GREEN (-950 2300);
DISPLAY INVISIBLE (-950 2300);
FORCEPROP 1 LAST HDL_TAP TRUE
J 2
(-1275 2125);
DISPLAY 0.872340 (-1275 2125);
DISPLAY INVISIBLE (-1275 2125);
FORCEPROP 1 LAST PATH I43
J 2
(-948 2250);
DISPLAY 0.872340 (-948 2250);
PAINT GREEN (-948 2250);
DISPLAY INVISIBLE (-948 2250);
FORCEADD TAP..1
R 2
(-950 2300);
FORCEPROP 3 LASTPIN (-900 2300) SIG_NAME M_H_CPU0_SB_DQ<27>
J 0
(-890 2310);
DISPLAY 0.659574 (-890 2310);
PAINT MONO (-890 2310);
DISPLAY INVISIBLE (-890 2310);
FORCEPROP 1 LASTPIN (-900 2300) BN 27
J 2
(-888 2308);
DISPLAY 0.680851 (-888 2308);
PAINT GREEN (-888 2308);
FORCEPROP 2 LAST CDS_LIB standard
J 0
(-950 2300);
DISPLAY INVISIBLE (-950 2300);
FORCEPROP 1 LAST BODY_TYPE PLUMBING
J 2
(-950 2350);
DISPLAY 0.872340 (-950 2350);
PAINT GREEN (-950 2350);
DISPLAY INVISIBLE (-950 2350);
FORCEPROP 1 LAST HDL_TAP TRUE
J 2
(-1275 2175);
DISPLAY 0.872340 (-1275 2175);
DISPLAY INVISIBLE (-1275 2175);
FORCEPROP 1 LAST PATH I44
J 2
(-948 2300);
DISPLAY 0.872340 (-948 2300);
PAINT GREEN (-948 2300);
DISPLAY INVISIBLE (-948 2300);
FORCEADD TAP..1
R 2
(-950 2350);
FORCEPROP 3 LASTPIN (-900 2350) SIG_NAME M_H_CPU0_SB_DQ<28>
J 0
(-890 2360);
DISPLAY 0.659574 (-890 2360);
PAINT MONO (-890 2360);
DISPLAY INVISIBLE (-890 2360);
FORCEPROP 1 LASTPIN (-900 2350) BN 28
J 2
(-888 2358);
DISPLAY 0.680851 (-888 2358);
PAINT GREEN (-888 2358);
FORCEPROP 2 LAST CDS_LIB standard
J 0
(-950 2350);
DISPLAY INVISIBLE (-950 2350);
FORCEPROP 1 LAST BODY_TYPE PLUMBING
J 2
(-950 2400);
DISPLAY 0.872340 (-950 2400);
PAINT GREEN (-950 2400);
DISPLAY INVISIBLE (-950 2400);
FORCEPROP 1 LAST HDL_TAP TRUE
J 2
(-1275 2225);
DISPLAY 0.872340 (-1275 2225);
DISPLAY INVISIBLE (-1275 2225);
FORCEPROP 1 LAST PATH I45
J 2
(-948 2350);
DISPLAY 0.872340 (-948 2350);
PAINT GREEN (-948 2350);
DISPLAY INVISIBLE (-948 2350);
FORCEADD TAP..1
R 2
(-950 2400);
FORCEPROP 3 LASTPIN (-900 2400) SIG_NAME M_H_CPU0_SB_DQ<29>
J 0
(-890 2410);
DISPLAY 0.659574 (-890 2410);
PAINT MONO (-890 2410);
DISPLAY INVISIBLE (-890 2410);
FORCEPROP 1 LASTPIN (-900 2400) BN 29
J 2
(-888 2408);
DISPLAY 0.680851 (-888 2408);
PAINT GREEN (-888 2408);
FORCEPROP 2 LAST CDS_LIB standard
J 0
(-950 2400);
DISPLAY INVISIBLE (-950 2400);
FORCEPROP 1 LAST BODY_TYPE PLUMBING
J 2
(-950 2450);
DISPLAY 0.872340 (-950 2450);
PAINT GREEN (-950 2450);
DISPLAY INVISIBLE (-950 2450);
FORCEPROP 1 LAST HDL_TAP TRUE
J 2
(-1275 2275);
DISPLAY 0.872340 (-1275 2275);
DISPLAY INVISIBLE (-1275 2275);
FORCEPROP 1 LAST PATH I46
J 2
(-948 2400);
DISPLAY 0.872340 (-948 2400);
PAINT GREEN (-948 2400);
DISPLAY INVISIBLE (-948 2400);
FORCEADD TAP..1
R 2
(-950 2500);
FORCEPROP 3 LASTPIN (-900 2500) SIG_NAME M_H_CPU0_SB_DQ<31>
J 0
(-890 2510);
DISPLAY 0.659574 (-890 2510);
PAINT MONO (-890 2510);
DISPLAY INVISIBLE (-890 2510);
FORCEPROP 1 LASTPIN (-900 2500) BN 31
J 2
(-888 2508);
DISPLAY 0.680851 (-888 2508);
PAINT GREEN (-888 2508);
FORCEPROP 2 LAST CDS_LIB standard
J 0
(-950 2500);
DISPLAY INVISIBLE (-950 2500);
FORCEPROP 1 LAST BODY_TYPE PLUMBING
J 2
(-950 2550);
DISPLAY 0.872340 (-950 2550);
PAINT GREEN (-950 2550);
DISPLAY INVISIBLE (-950 2550);
FORCEPROP 1 LAST HDL_TAP TRUE
J 2
(-1275 2375);
DISPLAY 0.872340 (-1275 2375);
DISPLAY INVISIBLE (-1275 2375);
FORCEPROP 1 LAST PATH I47
J 2
(-948 2500);
DISPLAY 0.872340 (-948 2500);
PAINT GREEN (-948 2500);
DISPLAY INVISIBLE (-948 2500);
FORCEADD TAP..1
R 2
(-950 2450);
FORCEPROP 3 LASTPIN (-900 2450) SIG_NAME M_H_CPU0_SB_DQ<30>
J 0
(-890 2460);
DISPLAY 0.659574 (-890 2460);
PAINT MONO (-890 2460);
DISPLAY INVISIBLE (-890 2460);
FORCEPROP 1 LASTPIN (-900 2450) BN 30
J 2
(-888 2458);
DISPLAY 0.680851 (-888 2458);
PAINT GREEN (-888 2458);
FORCEPROP 2 LAST CDS_LIB standard
J 0
(-950 2450);
DISPLAY INVISIBLE (-950 2450);
FORCEPROP 1 LAST BODY_TYPE PLUMBING
J 2
(-950 2500);
DISPLAY 0.872340 (-950 2500);
PAINT GREEN (-950 2500);
DISPLAY INVISIBLE (-950 2500);
FORCEPROP 1 LAST HDL_TAP TRUE
J 2
(-1275 2325);
DISPLAY 0.872340 (-1275 2325);
DISPLAY INVISIBLE (-1275 2325);
FORCEPROP 1 LAST PATH I48
J 2
(-948 2450);
DISPLAY 0.872340 (-948 2450);
PAINT GREEN (-948 2450);
DISPLAY INVISIBLE (-948 2450);
FORCEADD TAP..1
R 2
(-950 2650);
FORCEPROP 3 LASTPIN (-900 2650) SIG_NAME M_H_CPU0_SA_CB<2>
J 0
(-890 2660);
DISPLAY 0.659574 (-890 2660);
PAINT MONO (-890 2660);
DISPLAY INVISIBLE (-890 2660);
FORCEPROP 1 LASTPIN (-900 2650) BN 2
J 2
(-888 2658);
DISPLAY 0.680851 (-888 2658);
PAINT GREEN (-888 2658);
FORCEPROP 2 LAST CDS_LIB standard
J 0
(-950 2650);
DISPLAY INVISIBLE (-950 2650);
FORCEPROP 1 LAST BODY_TYPE PLUMBING
J 2
(-950 2700);
DISPLAY 0.872340 (-950 2700);
PAINT GREEN (-950 2700);
DISPLAY INVISIBLE (-950 2700);
FORCEPROP 1 LAST HDL_TAP TRUE
J 2
(-1275 2525);
DISPLAY 0.872340 (-1275 2525);
DISPLAY INVISIBLE (-1275 2525);
FORCEPROP 1 LAST PATH I49
J 2
(-948 2650);
DISPLAY 0.872340 (-948 2650);
PAINT GREEN (-948 2650);
DISPLAY INVISIBLE (-948 2650);
FORCEADD TAP..1
R 2
(-950 600);
FORCEPROP 3 LASTPIN (-900 600) SIG_NAME M_H_CPU0_SB_CB<1>
J 0
(-890 610);
DISPLAY 0.659574 (-890 610);
PAINT MONO (-890 610);
DISPLAY INVISIBLE (-890 610);
FORCEPROP 1 LASTPIN (-900 600) BN 1
J 2
(-888 608);
DISPLAY 0.680851 (-888 608);
PAINT GREEN (-888 608);
FORCEPROP 2 LAST CDS_LIB standard
J 0
(-950 600);
DISPLAY INVISIBLE (-950 600);
FORCEPROP 1 LAST BODY_TYPE PLUMBING
J 2
(-950 650);
DISPLAY 0.872340 (-950 650);
PAINT GREEN (-950 650);
DISPLAY INVISIBLE (-950 650);
FORCEPROP 1 LAST HDL_TAP TRUE
J 2
(-1275 475);
DISPLAY 0.872340 (-1275 475);
DISPLAY INVISIBLE (-1275 475);
FORCEPROP 1 LAST PATH I5
J 2
(-948 600);
DISPLAY 0.872340 (-948 600);
PAINT GREEN (-948 600);
DISPLAY INVISIBLE (-948 600);
FORCEADD TAP..1
R 2
(-950 2600);
FORCEPROP 3 LASTPIN (-900 2600) SIG_NAME M_H_CPU0_SA_CB<1>
J 0
(-890 2610);
DISPLAY 0.659574 (-890 2610);
PAINT MONO (-890 2610);
DISPLAY INVISIBLE (-890 2610);
FORCEPROP 1 LASTPIN (-900 2600) BN 1
J 2
(-888 2608);
DISPLAY 0.680851 (-888 2608);
PAINT GREEN (-888 2608);
FORCEPROP 2 LAST CDS_LIB standard
J 0
(-950 2600);
DISPLAY INVISIBLE (-950 2600);
FORCEPROP 1 LAST BODY_TYPE PLUMBING
J 2
(-950 2650);
DISPLAY 0.872340 (-950 2650);
PAINT GREEN (-950 2650);
DISPLAY INVISIBLE (-950 2650);
FORCEPROP 1 LAST HDL_TAP TRUE
J 2
(-1275 2475);
DISPLAY 0.872340 (-1275 2475);
DISPLAY INVISIBLE (-1275 2475);
FORCEPROP 1 LAST PATH I50
J 2
(-948 2600);
DISPLAY 0.872340 (-948 2600);
PAINT GREEN (-948 2600);
DISPLAY INVISIBLE (-948 2600);
FORCEADD TAP..1
R 2
(-950 2550);
FORCEPROP 3 LASTPIN (-900 2550) SIG_NAME M_H_CPU0_SA_CB<0>
J 0
(-890 2560);
DISPLAY 0.659574 (-890 2560);
PAINT MONO (-890 2560);
DISPLAY INVISIBLE (-890 2560);
FORCEPROP 1 LASTPIN (-900 2550) BN 0
J 2
(-888 2558);
DISPLAY 0.680851 (-888 2558);
PAINT GREEN (-888 2558);
FORCEPROP 2 LAST CDS_LIB standard
J 0
(-950 2550);
DISPLAY INVISIBLE (-950 2550);
FORCEPROP 1 LAST BODY_TYPE PLUMBING
J 2
(-950 2600);
DISPLAY 0.872340 (-950 2600);
PAINT GREEN (-950 2600);
DISPLAY INVISIBLE (-950 2600);
FORCEPROP 1 LAST HDL_TAP TRUE
J 2
(-1275 2425);
DISPLAY 0.872340 (-1275 2425);
DISPLAY INVISIBLE (-1275 2425);
FORCEPROP 1 LAST PATH I51
J 2
(-948 2550);
DISPLAY 0.872340 (-948 2550);
PAINT GREEN (-948 2550);
DISPLAY INVISIBLE (-948 2550);
FORCEADD OFFPAGE..3
R 2
(-1975 2925);
FORCEPROP 2 LAST $XR1 97 
J 0
(-2344 2925);
DISPLAY 0.638298 (-2344 2925);
PAINT MONO (-2344 2925);
FORCEPROP 2 LAST $XR0 96 
J 0
(-2254 2925);
DISPLAY 0.638298 (-2254 2925);
PAINT MONO (-2254 2925);
FORCEPROP 2 LAST CDS_LIB standard
J 0
(-1975 2925);
DISPLAY INVISIBLE (-1975 2925);
FORCEPROP 1 LAST OFFPAGE TRUE
J 2
(-2300 2800);
DISPLAY 0.872340 (-2300 2800);
DISPLAY INVISIBLE (-2300 2800);
FORCEPROP 1 LAST COMMENT_BODY TRUE
J 2
(-1925 2825);
DISPLAY 0.872340 (-1925 2825);
PAINT GREEN (-1925 2825);
DISPLAY INVISIBLE (-1925 2825);
FORCEPROP 2 LAST PATH I52
J 0
(-1925 3000);
DISPLAY 1.021277 (-1925 3000);
DISPLAY INVISIBLE (-1925 3000);
FORCEADD OFFPAGE..3
R 2
(-1975 4525);
FORCEPROP 2 LAST $XR1 97 
J 0
(-2344 4525);
DISPLAY 0.638298 (-2344 4525);
PAINT MONO (-2344 4525);
FORCEPROP 2 LAST $XR0 96 
J 0
(-2254 4525);
DISPLAY 0.638298 (-2254 4525);
PAINT MONO (-2254 4525);
FORCEPROP 2 LAST CDS_LIB standard
J 0
(-1975 4525);
DISPLAY INVISIBLE (-1975 4525);
FORCEPROP 1 LAST OFFPAGE TRUE
J 2
(-2300 4400);
DISPLAY 0.872340 (-2300 4400);
DISPLAY INVISIBLE (-2300 4400);
FORCEPROP 1 LAST COMMENT_BODY TRUE
J 2
(-1925 4425);
DISPLAY 0.872340 (-1925 4425);
PAINT GREEN (-1925 4425);
DISPLAY INVISIBLE (-1925 4425);
FORCEPROP 2 LAST PATH I53
J 0
(-1925 4600);
DISPLAY 1.021277 (-1925 4600);
DISPLAY INVISIBLE (-1925 4600);
FORCEADD TAP..1
R 2
(-950 2750);
FORCEPROP 3 LASTPIN (-900 2750) SIG_NAME M_H_CPU0_SA_CB<4>
J 0
(-890 2760);
DISPLAY 0.659574 (-890 2760);
PAINT MONO (-890 2760);
DISPLAY INVISIBLE (-890 2760);
FORCEPROP 1 LASTPIN (-900 2750) BN 4
J 2
(-888 2758);
DISPLAY 0.680851 (-888 2758);
PAINT GREEN (-888 2758);
FORCEPROP 2 LAST CDS_LIB standard
J 0
(-950 2750);
DISPLAY INVISIBLE (-950 2750);
FORCEPROP 1 LAST BODY_TYPE PLUMBING
J 2
(-950 2800);
DISPLAY 0.872340 (-950 2800);
PAINT GREEN (-950 2800);
DISPLAY INVISIBLE (-950 2800);
FORCEPROP 1 LAST HDL_TAP TRUE
J 2
(-1275 2625);
DISPLAY 0.872340 (-1275 2625);
DISPLAY INVISIBLE (-1275 2625);
FORCEPROP 1 LAST PATH I54
J 2
(-948 2750);
DISPLAY 0.872340 (-948 2750);
PAINT GREEN (-948 2750);
DISPLAY INVISIBLE (-948 2750);
FORCEADD TAP..1
R 2
(-950 2800);
FORCEPROP 3 LASTPIN (-900 2800) SIG_NAME M_H_CPU0_SA_CB<5>
J 0
(-890 2810);
DISPLAY 0.659574 (-890 2810);
PAINT MONO (-890 2810);
DISPLAY INVISIBLE (-890 2810);
FORCEPROP 1 LASTPIN (-900 2800) BN 5
J 2
(-888 2808);
DISPLAY 0.680851 (-888 2808);
PAINT GREEN (-888 2808);
FORCEPROP 2 LAST CDS_LIB standard
J 0
(-950 2800);
DISPLAY INVISIBLE (-950 2800);
FORCEPROP 1 LAST BODY_TYPE PLUMBING
J 2
(-950 2850);
DISPLAY 0.872340 (-950 2850);
PAINT GREEN (-950 2850);
DISPLAY INVISIBLE (-950 2850);
FORCEPROP 1 LAST HDL_TAP TRUE
J 2
(-1275 2675);
DISPLAY 0.872340 (-1275 2675);
DISPLAY INVISIBLE (-1275 2675);
FORCEPROP 1 LAST PATH I55
J 2
(-948 2800);
DISPLAY 0.872340 (-948 2800);
PAINT GREEN (-948 2800);
DISPLAY INVISIBLE (-948 2800);
FORCEADD TAP..1
R 2
(-950 2700);
FORCEPROP 3 LASTPIN (-900 2700) SIG_NAME M_H_CPU0_SA_CB<3>
J 0
(-890 2710);
DISPLAY 0.659574 (-890 2710);
PAINT MONO (-890 2710);
DISPLAY INVISIBLE (-890 2710);
FORCEPROP 1 LASTPIN (-900 2700) BN 3
J 2
(-888 2708);
DISPLAY 0.680851 (-888 2708);
PAINT GREEN (-888 2708);
FORCEPROP 2 LAST CDS_LIB standard
J 0
(-950 2700);
DISPLAY INVISIBLE (-950 2700);
FORCEPROP 1 LAST BODY_TYPE PLUMBING
J 2
(-950 2750);
DISPLAY 0.872340 (-950 2750);
PAINT GREEN (-950 2750);
DISPLAY INVISIBLE (-950 2750);
FORCEPROP 1 LAST HDL_TAP TRUE
J 2
(-1275 2575);
DISPLAY 0.872340 (-1275 2575);
DISPLAY INVISIBLE (-1275 2575);
FORCEPROP 1 LAST PATH I56
J 2
(-948 2700);
DISPLAY 0.872340 (-948 2700);
PAINT GREEN (-948 2700);
DISPLAY INVISIBLE (-948 2700);
FORCEADD TAP..1
R 2
(-950 2900);
FORCEPROP 3 LASTPIN (-900 2900) SIG_NAME M_H_CPU0_SA_CB<7>
J 0
(-890 2910);
DISPLAY 0.659574 (-890 2910);
PAINT MONO (-890 2910);
DISPLAY INVISIBLE (-890 2910);
FORCEPROP 1 LASTPIN (-900 2900) BN 7
J 2
(-888 2908);
DISPLAY 0.680851 (-888 2908);
PAINT GREEN (-888 2908);
FORCEPROP 2 LAST CDS_LIB standard
J 0
(-950 2900);
DISPLAY INVISIBLE (-950 2900);
FORCEPROP 1 LAST BODY_TYPE PLUMBING
J 2
(-950 2950);
DISPLAY 0.872340 (-950 2950);
PAINT GREEN (-950 2950);
DISPLAY INVISIBLE (-950 2950);
FORCEPROP 1 LAST HDL_TAP TRUE
J 2
(-1275 2775);
DISPLAY 0.872340 (-1275 2775);
DISPLAY INVISIBLE (-1275 2775);
FORCEPROP 1 LAST PATH I57
J 2
(-948 2900);
DISPLAY 0.872340 (-948 2900);
PAINT GREEN (-948 2900);
DISPLAY INVISIBLE (-948 2900);
FORCEADD TAP..1
R 2
(-950 2850);
FORCEPROP 3 LASTPIN (-900 2850) SIG_NAME M_H_CPU0_SA_CB<6>
J 0
(-890 2860);
DISPLAY 0.659574 (-890 2860);
PAINT MONO (-890 2860);
DISPLAY INVISIBLE (-890 2860);
FORCEPROP 1 LASTPIN (-900 2850) BN 6
J 2
(-888 2858);
DISPLAY 0.680851 (-888 2858);
PAINT GREEN (-888 2858);
FORCEPROP 2 LAST CDS_LIB standard
J 0
(-950 2850);
DISPLAY INVISIBLE (-950 2850);
FORCEPROP 1 LAST BODY_TYPE PLUMBING
J 2
(-950 2900);
DISPLAY 0.872340 (-950 2900);
PAINT GREEN (-950 2900);
DISPLAY INVISIBLE (-950 2900);
FORCEPROP 1 LAST HDL_TAP TRUE
J 2
(-1275 2725);
DISPLAY 0.872340 (-1275 2725);
DISPLAY INVISIBLE (-1275 2725);
FORCEPROP 1 LAST PATH I58
J 2
(-948 2850);
DISPLAY 0.872340 (-948 2850);
PAINT GREEN (-948 2850);
DISPLAY INVISIBLE (-948 2850);
FORCEADD TAP..1
R 2
(-950 3000);
FORCEPROP 3 LASTPIN (-900 3000) SIG_NAME M_H_CPU0_SA_DQ<1>
J 0
(-890 3010);
DISPLAY 0.659574 (-890 3010);
PAINT MONO (-890 3010);
DISPLAY INVISIBLE (-890 3010);
FORCEPROP 1 LASTPIN (-900 3000) BN 1
J 2
(-888 3008);
DISPLAY 0.680851 (-888 3008);
PAINT GREEN (-888 3008);
FORCEPROP 2 LAST CDS_LIB standard
J 0
(-950 3000);
DISPLAY INVISIBLE (-950 3000);
FORCEPROP 1 LAST BODY_TYPE PLUMBING
J 2
(-950 3050);
DISPLAY 0.872340 (-950 3050);
PAINT GREEN (-950 3050);
DISPLAY INVISIBLE (-950 3050);
FORCEPROP 1 LAST HDL_TAP TRUE
J 2
(-1275 2875);
DISPLAY 0.872340 (-1275 2875);
DISPLAY INVISIBLE (-1275 2875);
FORCEPROP 1 LAST PATH I59
J 2
(-948 3000);
DISPLAY 0.872340 (-948 3000);
PAINT GREEN (-948 3000);
DISPLAY INVISIBLE (-948 3000);
FORCEADD TAP..1
R 2
(-950 550);
FORCEPROP 3 LASTPIN (-900 550) SIG_NAME M_H_CPU0_SB_CB<0>
J 0
(-890 560);
DISPLAY 0.659574 (-890 560);
PAINT MONO (-890 560);
DISPLAY INVISIBLE (-890 560);
FORCEPROP 1 LASTPIN (-900 550) BN 0
J 2
(-888 558);
DISPLAY 0.680851 (-888 558);
PAINT GREEN (-888 558);
FORCEPROP 2 LAST CDS_LIB standard
J 0
(-950 550);
DISPLAY INVISIBLE (-950 550);
FORCEPROP 1 LAST BODY_TYPE PLUMBING
J 2
(-950 600);
DISPLAY 0.872340 (-950 600);
PAINT GREEN (-950 600);
DISPLAY INVISIBLE (-950 600);
FORCEPROP 1 LAST HDL_TAP TRUE
J 2
(-1275 425);
DISPLAY 0.872340 (-1275 425);
DISPLAY INVISIBLE (-1275 425);
FORCEPROP 1 LAST PATH I6
J 2
(-948 550);
DISPLAY 0.872340 (-948 550);
PAINT GREEN (-948 550);
DISPLAY INVISIBLE (-948 550);
FORCEADD TAP..1
R 2
(-950 2950);
FORCEPROP 3 LASTPIN (-900 2950) SIG_NAME M_H_CPU0_SA_DQ<0>
J 0
(-890 2960);
DISPLAY 0.659574 (-890 2960);
PAINT MONO (-890 2960);
DISPLAY INVISIBLE (-890 2960);
FORCEPROP 1 LASTPIN (-900 2950) BN 0
J 2
(-888 2958);
DISPLAY 0.680851 (-888 2958);
PAINT GREEN (-888 2958);
FORCEPROP 2 LAST CDS_LIB standard
J 0
(-950 2950);
DISPLAY INVISIBLE (-950 2950);
FORCEPROP 1 LAST BODY_TYPE PLUMBING
J 2
(-950 3000);
DISPLAY 0.872340 (-950 3000);
PAINT GREEN (-950 3000);
DISPLAY INVISIBLE (-950 3000);
FORCEPROP 1 LAST HDL_TAP TRUE
J 2
(-1275 2825);
DISPLAY 0.872340 (-1275 2825);
DISPLAY INVISIBLE (-1275 2825);
FORCEPROP 1 LAST PATH I60
J 2
(-948 2950);
DISPLAY 0.872340 (-948 2950);
PAINT GREEN (-948 2950);
DISPLAY INVISIBLE (-948 2950);
FORCEADD TAP..1
R 2
(-950 3050);
FORCEPROP 3 LASTPIN (-900 3050) SIG_NAME M_H_CPU0_SA_DQ<2>
J 0
(-890 3060);
DISPLAY 0.659574 (-890 3060);
PAINT MONO (-890 3060);
DISPLAY INVISIBLE (-890 3060);
FORCEPROP 1 LASTPIN (-900 3050) BN 2
J 2
(-888 3058);
DISPLAY 0.680851 (-888 3058);
PAINT GREEN (-888 3058);
FORCEPROP 2 LAST CDS_LIB standard
J 0
(-950 3050);
DISPLAY INVISIBLE (-950 3050);
FORCEPROP 1 LAST BODY_TYPE PLUMBING
J 2
(-950 3100);
DISPLAY 0.872340 (-950 3100);
PAINT GREEN (-950 3100);
DISPLAY INVISIBLE (-950 3100);
FORCEPROP 1 LAST HDL_TAP TRUE
J 2
(-1275 2925);
DISPLAY 0.872340 (-1275 2925);
DISPLAY INVISIBLE (-1275 2925);
FORCEPROP 1 LAST PATH I61
J 2
(-948 3050);
DISPLAY 0.872340 (-948 3050);
PAINT GREEN (-948 3050);
DISPLAY INVISIBLE (-948 3050);
FORCEADD TAP..1
R 2
(-950 3150);
FORCEPROP 3 LASTPIN (-900 3150) SIG_NAME M_H_CPU0_SA_DQ<4>
J 0
(-890 3160);
DISPLAY 0.659574 (-890 3160);
PAINT MONO (-890 3160);
DISPLAY INVISIBLE (-890 3160);
FORCEPROP 1 LASTPIN (-900 3150) BN 4
J 2
(-888 3158);
DISPLAY 0.680851 (-888 3158);
PAINT GREEN (-888 3158);
FORCEPROP 2 LAST CDS_LIB standard
J 0
(-950 3150);
DISPLAY INVISIBLE (-950 3150);
FORCEPROP 1 LAST BODY_TYPE PLUMBING
J 2
(-950 3200);
DISPLAY 0.872340 (-950 3200);
PAINT GREEN (-950 3200);
DISPLAY INVISIBLE (-950 3200);
FORCEPROP 1 LAST HDL_TAP TRUE
J 2
(-1275 3025);
DISPLAY 0.872340 (-1275 3025);
DISPLAY INVISIBLE (-1275 3025);
FORCEPROP 1 LAST PATH I62
J 2
(-948 3150);
DISPLAY 0.872340 (-948 3150);
PAINT GREEN (-948 3150);
DISPLAY INVISIBLE (-948 3150);
FORCEADD TAP..1
R 2
(-950 3100);
FORCEPROP 3 LASTPIN (-900 3100) SIG_NAME M_H_CPU0_SA_DQ<3>
J 0
(-890 3110);
DISPLAY 0.659574 (-890 3110);
PAINT MONO (-890 3110);
DISPLAY INVISIBLE (-890 3110);
FORCEPROP 1 LASTPIN (-900 3100) BN 3
J 2
(-888 3108);
DISPLAY 0.680851 (-888 3108);
PAINT GREEN (-888 3108);
FORCEPROP 2 LAST CDS_LIB standard
J 0
(-950 3100);
DISPLAY INVISIBLE (-950 3100);
FORCEPROP 1 LAST BODY_TYPE PLUMBING
J 2
(-950 3150);
DISPLAY 0.872340 (-950 3150);
PAINT GREEN (-950 3150);
DISPLAY INVISIBLE (-950 3150);
FORCEPROP 1 LAST HDL_TAP TRUE
J 2
(-1275 2975);
DISPLAY 0.872340 (-1275 2975);
DISPLAY INVISIBLE (-1275 2975);
FORCEPROP 1 LAST PATH I63
J 2
(-948 3100);
DISPLAY 0.872340 (-948 3100);
PAINT GREEN (-948 3100);
DISPLAY INVISIBLE (-948 3100);
FORCEADD TAP..1
R 2
(-950 3200);
FORCEPROP 3 LASTPIN (-900 3200) SIG_NAME M_H_CPU0_SA_DQ<5>
J 0
(-890 3210);
DISPLAY 0.659574 (-890 3210);
PAINT MONO (-890 3210);
DISPLAY INVISIBLE (-890 3210);
FORCEPROP 1 LASTPIN (-900 3200) BN 5
J 2
(-888 3208);
DISPLAY 0.680851 (-888 3208);
PAINT GREEN (-888 3208);
FORCEPROP 2 LAST CDS_LIB standard
J 0
(-950 3200);
DISPLAY INVISIBLE (-950 3200);
FORCEPROP 1 LAST BODY_TYPE PLUMBING
J 2
(-950 3250);
DISPLAY 0.872340 (-950 3250);
PAINT GREEN (-950 3250);
DISPLAY INVISIBLE (-950 3250);
FORCEPROP 1 LAST HDL_TAP TRUE
J 2
(-1275 3075);
DISPLAY 0.872340 (-1275 3075);
DISPLAY INVISIBLE (-1275 3075);
FORCEPROP 1 LAST PATH I64
J 2
(-948 3200);
DISPLAY 0.872340 (-948 3200);
PAINT GREEN (-948 3200);
DISPLAY INVISIBLE (-948 3200);
FORCEADD TAP..1
R 2
(-950 3300);
FORCEPROP 3 LASTPIN (-900 3300) SIG_NAME M_H_CPU0_SA_DQ<7>
J 0
(-890 3310);
DISPLAY 0.659574 (-890 3310);
PAINT MONO (-890 3310);
DISPLAY INVISIBLE (-890 3310);
FORCEPROP 1 LASTPIN (-900 3300) BN 7
J 2
(-888 3308);
DISPLAY 0.680851 (-888 3308);
PAINT GREEN (-888 3308);
FORCEPROP 2 LAST CDS_LIB standard
J 0
(-950 3300);
DISPLAY INVISIBLE (-950 3300);
FORCEPROP 1 LAST BODY_TYPE PLUMBING
J 2
(-950 3350);
DISPLAY 0.872340 (-950 3350);
PAINT GREEN (-950 3350);
DISPLAY INVISIBLE (-950 3350);
FORCEPROP 1 LAST HDL_TAP TRUE
J 2
(-1275 3175);
DISPLAY 0.872340 (-1275 3175);
DISPLAY INVISIBLE (-1275 3175);
FORCEPROP 1 LAST PATH I65
J 2
(-948 3300);
DISPLAY 0.872340 (-948 3300);
PAINT GREEN (-948 3300);
DISPLAY INVISIBLE (-948 3300);
FORCEADD TAP..1
R 2
(-950 3250);
FORCEPROP 3 LASTPIN (-900 3250) SIG_NAME M_H_CPU0_SA_DQ<6>
J 0
(-890 3260);
DISPLAY 0.659574 (-890 3260);
PAINT MONO (-890 3260);
DISPLAY INVISIBLE (-890 3260);
FORCEPROP 1 LASTPIN (-900 3250) BN 6
J 2
(-888 3258);
DISPLAY 0.680851 (-888 3258);
PAINT GREEN (-888 3258);
FORCEPROP 2 LAST CDS_LIB standard
J 0
(-950 3250);
DISPLAY INVISIBLE (-950 3250);
FORCEPROP 1 LAST BODY_TYPE PLUMBING
J 2
(-950 3300);
DISPLAY 0.872340 (-950 3300);
PAINT GREEN (-950 3300);
DISPLAY INVISIBLE (-950 3300);
FORCEPROP 1 LAST HDL_TAP TRUE
J 2
(-1275 3125);
DISPLAY 0.872340 (-1275 3125);
DISPLAY INVISIBLE (-1275 3125);
FORCEPROP 1 LAST PATH I66
J 2
(-948 3250);
DISPLAY 0.872340 (-948 3250);
PAINT GREEN (-948 3250);
DISPLAY INVISIBLE (-948 3250);
FORCEADD TAP..1
R 2
(-950 3400);
FORCEPROP 3 LASTPIN (-900 3400) SIG_NAME M_H_CPU0_SA_DQ<9>
J 0
(-890 3410);
DISPLAY 0.659574 (-890 3410);
PAINT MONO (-890 3410);
DISPLAY INVISIBLE (-890 3410);
FORCEPROP 1 LASTPIN (-900 3400) BN 9
J 2
(-888 3408);
DISPLAY 0.680851 (-888 3408);
PAINT GREEN (-888 3408);
FORCEPROP 2 LAST CDS_LIB standard
J 0
(-950 3400);
DISPLAY INVISIBLE (-950 3400);
FORCEPROP 1 LAST BODY_TYPE PLUMBING
J 2
(-950 3450);
DISPLAY 0.872340 (-950 3450);
PAINT GREEN (-950 3450);
DISPLAY INVISIBLE (-950 3450);
FORCEPROP 1 LAST HDL_TAP TRUE
J 2
(-1275 3275);
DISPLAY 0.872340 (-1275 3275);
DISPLAY INVISIBLE (-1275 3275);
FORCEPROP 1 LAST PATH I67
J 2
(-948 3400);
DISPLAY 0.872340 (-948 3400);
PAINT GREEN (-948 3400);
DISPLAY INVISIBLE (-948 3400);
FORCEADD TAP..1
R 2
(-950 3350);
FORCEPROP 3 LASTPIN (-900 3350) SIG_NAME M_H_CPU0_SA_DQ<8>
J 0
(-890 3360);
DISPLAY 0.659574 (-890 3360);
PAINT MONO (-890 3360);
DISPLAY INVISIBLE (-890 3360);
FORCEPROP 1 LASTPIN (-900 3350) BN 8
J 2
(-888 3358);
DISPLAY 0.680851 (-888 3358);
PAINT GREEN (-888 3358);
FORCEPROP 2 LAST CDS_LIB standard
J 0
(-950 3350);
DISPLAY INVISIBLE (-950 3350);
FORCEPROP 1 LAST BODY_TYPE PLUMBING
J 2
(-950 3400);
DISPLAY 0.872340 (-950 3400);
PAINT GREEN (-950 3400);
DISPLAY INVISIBLE (-950 3400);
FORCEPROP 1 LAST HDL_TAP TRUE
J 2
(-1275 3225);
DISPLAY 0.872340 (-1275 3225);
DISPLAY INVISIBLE (-1275 3225);
FORCEPROP 1 LAST PATH I68
J 2
(-948 3350);
DISPLAY 0.872340 (-948 3350);
PAINT GREEN (-948 3350);
DISPLAY INVISIBLE (-948 3350);
FORCEADD TAP..1
R 2
(-950 3450);
FORCEPROP 3 LASTPIN (-900 3450) SIG_NAME M_H_CPU0_SA_DQ<10>
J 0
(-890 3460);
DISPLAY 0.659574 (-890 3460);
PAINT MONO (-890 3460);
DISPLAY INVISIBLE (-890 3460);
FORCEPROP 1 LASTPIN (-900 3450) BN 10
J 2
(-888 3458);
DISPLAY 0.680851 (-888 3458);
PAINT GREEN (-888 3458);
FORCEPROP 2 LAST CDS_LIB standard
J 0
(-950 3450);
DISPLAY INVISIBLE (-950 3450);
FORCEPROP 1 LAST BODY_TYPE PLUMBING
J 2
(-950 3500);
DISPLAY 0.872340 (-950 3500);
PAINT GREEN (-950 3500);
DISPLAY INVISIBLE (-950 3500);
FORCEPROP 1 LAST HDL_TAP TRUE
J 2
(-1275 3325);
DISPLAY 0.872340 (-1275 3325);
DISPLAY INVISIBLE (-1275 3325);
FORCEPROP 1 LAST PATH I69
J 2
(-948 3450);
DISPLAY 0.872340 (-948 3450);
PAINT GREEN (-948 3450);
DISPLAY INVISIBLE (-948 3450);
FORCEADD TAP..1
R 2
(-950 400);
FORCEPROP 3 LASTPIN (-900 400) SIG_NAME M_H_CPU0_CLK_DP<0>
J 0
(-890 410);
DISPLAY 0.659574 (-890 410);
PAINT MONO (-890 410);
DISPLAY INVISIBLE (-890 410);
FORCEPROP 1 LASTPIN (-900 400) BN 0
J 2
(-888 408);
DISPLAY 0.680851 (-888 408);
PAINT GREEN (-888 408);
FORCEPROP 2 LAST CDS_LIB standard
J 0
(-950 400);
DISPLAY INVISIBLE (-950 400);
FORCEPROP 1 LAST BODY_TYPE PLUMBING
J 2
(-950 450);
DISPLAY 0.872340 (-950 450);
PAINT GREEN (-950 450);
DISPLAY INVISIBLE (-950 450);
FORCEPROP 1 LAST HDL_TAP TRUE
J 2
(-1275 275);
DISPLAY 0.872340 (-1275 275);
DISPLAY INVISIBLE (-1275 275);
FORCEPROP 1 LAST PATH I7
J 2
(-948 400);
DISPLAY 0.872340 (-948 400);
PAINT GREEN (-948 400);
DISPLAY INVISIBLE (-948 400);
FORCEADD TAP..1
R 2
(-950 3500);
FORCEPROP 3 LASTPIN (-900 3500) SIG_NAME M_H_CPU0_SA_DQ<11>
J 0
(-890 3510);
DISPLAY 0.659574 (-890 3510);
PAINT MONO (-890 3510);
DISPLAY INVISIBLE (-890 3510);
FORCEPROP 1 LASTPIN (-900 3500) BN 11
J 2
(-888 3508);
DISPLAY 0.680851 (-888 3508);
PAINT GREEN (-888 3508);
FORCEPROP 2 LAST CDS_LIB standard
J 0
(-950 3500);
DISPLAY INVISIBLE (-950 3500);
FORCEPROP 1 LAST BODY_TYPE PLUMBING
J 2
(-950 3550);
DISPLAY 0.872340 (-950 3550);
PAINT GREEN (-950 3550);
DISPLAY INVISIBLE (-950 3550);
FORCEPROP 1 LAST HDL_TAP TRUE
J 2
(-1275 3375);
DISPLAY 0.872340 (-1275 3375);
DISPLAY INVISIBLE (-1275 3375);
FORCEPROP 1 LAST PATH I70
J 2
(-948 3500);
DISPLAY 0.872340 (-948 3500);
PAINT GREEN (-948 3500);
DISPLAY INVISIBLE (-948 3500);
FORCEADD TAP..1
R 2
(-950 3550);
FORCEPROP 3 LASTPIN (-900 3550) SIG_NAME M_H_CPU0_SA_DQ<12>
J 0
(-890 3560);
DISPLAY 0.659574 (-890 3560);
PAINT MONO (-890 3560);
DISPLAY INVISIBLE (-890 3560);
FORCEPROP 1 LASTPIN (-900 3550) BN 12
J 2
(-888 3558);
DISPLAY 0.680851 (-888 3558);
PAINT GREEN (-888 3558);
FORCEPROP 2 LAST CDS_LIB standard
J 0
(-950 3550);
DISPLAY INVISIBLE (-950 3550);
FORCEPROP 1 LAST BODY_TYPE PLUMBING
J 2
(-950 3600);
DISPLAY 0.872340 (-950 3600);
PAINT GREEN (-950 3600);
DISPLAY INVISIBLE (-950 3600);
FORCEPROP 1 LAST HDL_TAP TRUE
J 2
(-1275 3425);
DISPLAY 0.872340 (-1275 3425);
DISPLAY INVISIBLE (-1275 3425);
FORCEPROP 1 LAST PATH I71
J 2
(-948 3550);
DISPLAY 0.872340 (-948 3550);
PAINT GREEN (-948 3550);
DISPLAY INVISIBLE (-948 3550);
FORCEADD TAP..1
R 2
(-950 3650);
FORCEPROP 3 LASTPIN (-900 3650) SIG_NAME M_H_CPU0_SA_DQ<14>
J 0
(-890 3660);
DISPLAY 0.659574 (-890 3660);
PAINT MONO (-890 3660);
DISPLAY INVISIBLE (-890 3660);
FORCEPROP 1 LASTPIN (-900 3650) BN 14
J 2
(-888 3658);
DISPLAY 0.680851 (-888 3658);
PAINT GREEN (-888 3658);
FORCEPROP 2 LAST CDS_LIB standard
J 0
(-950 3650);
DISPLAY INVISIBLE (-950 3650);
FORCEPROP 1 LAST BODY_TYPE PLUMBING
J 2
(-950 3700);
DISPLAY 0.872340 (-950 3700);
PAINT GREEN (-950 3700);
DISPLAY INVISIBLE (-950 3700);
FORCEPROP 1 LAST HDL_TAP TRUE
J 2
(-1275 3525);
DISPLAY 0.872340 (-1275 3525);
DISPLAY INVISIBLE (-1275 3525);
FORCEPROP 1 LAST PATH I72
J 2
(-948 3650);
DISPLAY 0.872340 (-948 3650);
PAINT GREEN (-948 3650);
DISPLAY INVISIBLE (-948 3650);
FORCEADD TAP..1
R 2
(-950 3600);
FORCEPROP 3 LASTPIN (-900 3600) SIG_NAME M_H_CPU0_SA_DQ<13>
J 0
(-890 3610);
DISPLAY 0.659574 (-890 3610);
PAINT MONO (-890 3610);
DISPLAY INVISIBLE (-890 3610);
FORCEPROP 1 LASTPIN (-900 3600) BN 13
J 2
(-888 3608);
DISPLAY 0.680851 (-888 3608);
PAINT GREEN (-888 3608);
FORCEPROP 2 LAST CDS_LIB standard
J 0
(-950 3600);
DISPLAY INVISIBLE (-950 3600);
FORCEPROP 1 LAST BODY_TYPE PLUMBING
J 2
(-950 3650);
DISPLAY 0.872340 (-950 3650);
PAINT GREEN (-950 3650);
DISPLAY INVISIBLE (-950 3650);
FORCEPROP 1 LAST HDL_TAP TRUE
J 2
(-1275 3475);
DISPLAY 0.872340 (-1275 3475);
DISPLAY INVISIBLE (-1275 3475);
FORCEPROP 1 LAST PATH I73
J 2
(-948 3600);
DISPLAY 0.872340 (-948 3600);
PAINT GREEN (-948 3600);
DISPLAY INVISIBLE (-948 3600);
FORCEADD TAP..1
R 2
(-950 3700);
FORCEPROP 3 LASTPIN (-900 3700) SIG_NAME M_H_CPU0_SA_DQ<15>
J 0
(-890 3710);
DISPLAY 0.659574 (-890 3710);
PAINT MONO (-890 3710);
DISPLAY INVISIBLE (-890 3710);
FORCEPROP 1 LASTPIN (-900 3700) BN 15
J 2
(-888 3708);
DISPLAY 0.680851 (-888 3708);
PAINT GREEN (-888 3708);
FORCEPROP 2 LAST CDS_LIB standard
J 0
(-950 3700);
DISPLAY INVISIBLE (-950 3700);
FORCEPROP 1 LAST BODY_TYPE PLUMBING
J 2
(-950 3750);
DISPLAY 0.872340 (-950 3750);
PAINT GREEN (-950 3750);
DISPLAY INVISIBLE (-950 3750);
FORCEPROP 1 LAST HDL_TAP TRUE
J 2
(-1275 3575);
DISPLAY 0.872340 (-1275 3575);
DISPLAY INVISIBLE (-1275 3575);
FORCEPROP 1 LAST PATH I74
J 2
(-948 3700);
DISPLAY 0.872340 (-948 3700);
PAINT GREEN (-948 3700);
DISPLAY INVISIBLE (-948 3700);
FORCEADD TAP..1
R 2
(-950 3750);
FORCEPROP 3 LASTPIN (-900 3750) SIG_NAME M_H_CPU0_SA_DQ<16>
J 0
(-890 3760);
DISPLAY 0.659574 (-890 3760);
PAINT MONO (-890 3760);
DISPLAY INVISIBLE (-890 3760);
FORCEPROP 1 LASTPIN (-900 3750) BN 16
J 2
(-888 3758);
DISPLAY 0.680851 (-888 3758);
PAINT GREEN (-888 3758);
FORCEPROP 2 LAST CDS_LIB standard
J 0
(-950 3750);
DISPLAY INVISIBLE (-950 3750);
FORCEPROP 1 LAST BODY_TYPE PLUMBING
J 2
(-950 3800);
DISPLAY 0.872340 (-950 3800);
PAINT GREEN (-950 3800);
DISPLAY INVISIBLE (-950 3800);
FORCEPROP 1 LAST HDL_TAP TRUE
J 2
(-1275 3625);
DISPLAY 0.872340 (-1275 3625);
DISPLAY INVISIBLE (-1275 3625);
FORCEPROP 1 LAST PATH I75
J 2
(-948 3750);
DISPLAY 0.872340 (-948 3750);
PAINT GREEN (-948 3750);
DISPLAY INVISIBLE (-948 3750);
FORCEADD TAP..1
R 2
(-950 3800);
FORCEPROP 3 LASTPIN (-900 3800) SIG_NAME M_H_CPU0_SA_DQ<17>
J 0
(-890 3810);
DISPLAY 0.659574 (-890 3810);
PAINT MONO (-890 3810);
DISPLAY INVISIBLE (-890 3810);
FORCEPROP 1 LASTPIN (-900 3800) BN 17
J 2
(-888 3808);
DISPLAY 0.680851 (-888 3808);
PAINT GREEN (-888 3808);
FORCEPROP 2 LAST CDS_LIB standard
J 0
(-950 3800);
DISPLAY INVISIBLE (-950 3800);
FORCEPROP 1 LAST BODY_TYPE PLUMBING
J 2
(-950 3850);
DISPLAY 0.872340 (-950 3850);
PAINT GREEN (-950 3850);
DISPLAY INVISIBLE (-950 3850);
FORCEPROP 1 LAST HDL_TAP TRUE
J 2
(-1275 3675);
DISPLAY 0.872340 (-1275 3675);
DISPLAY INVISIBLE (-1275 3675);
FORCEPROP 1 LAST PATH I76
J 2
(-948 3800);
DISPLAY 0.872340 (-948 3800);
PAINT GREEN (-948 3800);
DISPLAY INVISIBLE (-948 3800);
FORCEADD TAP..1
R 2
(-950 3900);
FORCEPROP 3 LASTPIN (-900 3900) SIG_NAME M_H_CPU0_SA_DQ<19>
J 0
(-890 3910);
DISPLAY 0.659574 (-890 3910);
PAINT MONO (-890 3910);
DISPLAY INVISIBLE (-890 3910);
FORCEPROP 1 LASTPIN (-900 3900) BN 19
J 2
(-888 3908);
DISPLAY 0.680851 (-888 3908);
PAINT GREEN (-888 3908);
FORCEPROP 2 LAST CDS_LIB standard
J 0
(-950 3900);
DISPLAY INVISIBLE (-950 3900);
FORCEPROP 1 LAST BODY_TYPE PLUMBING
J 2
(-950 3950);
DISPLAY 0.872340 (-950 3950);
PAINT GREEN (-950 3950);
DISPLAY INVISIBLE (-950 3950);
FORCEPROP 1 LAST HDL_TAP TRUE
J 2
(-1275 3775);
DISPLAY 0.872340 (-1275 3775);
DISPLAY INVISIBLE (-1275 3775);
FORCEPROP 1 LAST PATH I77
J 2
(-948 3900);
DISPLAY 0.872340 (-948 3900);
PAINT GREEN (-948 3900);
DISPLAY INVISIBLE (-948 3900);
FORCEADD TAP..1
R 2
(-950 3950);
FORCEPROP 3 LASTPIN (-900 3950) SIG_NAME M_H_CPU0_SA_DQ<20>
J 0
(-890 3960);
DISPLAY 0.659574 (-890 3960);
PAINT MONO (-890 3960);
DISPLAY INVISIBLE (-890 3960);
FORCEPROP 1 LASTPIN (-900 3950) BN 20
J 2
(-888 3958);
DISPLAY 0.680851 (-888 3958);
PAINT GREEN (-888 3958);
FORCEPROP 2 LAST CDS_LIB standard
J 0
(-950 3950);
DISPLAY INVISIBLE (-950 3950);
FORCEPROP 1 LAST BODY_TYPE PLUMBING
J 2
(-950 4000);
DISPLAY 0.872340 (-950 4000);
PAINT GREEN (-950 4000);
DISPLAY INVISIBLE (-950 4000);
FORCEPROP 1 LAST HDL_TAP TRUE
J 2
(-1275 3825);
DISPLAY 0.872340 (-1275 3825);
DISPLAY INVISIBLE (-1275 3825);
FORCEPROP 1 LAST PATH I78
J 2
(-948 3950);
DISPLAY 0.872340 (-948 3950);
PAINT GREEN (-948 3950);
DISPLAY INVISIBLE (-948 3950);
FORCEADD TAP..1
R 2
(-950 3850);
FORCEPROP 3 LASTPIN (-900 3850) SIG_NAME M_H_CPU0_SA_DQ<18>
J 0
(-890 3860);
DISPLAY 0.659574 (-890 3860);
PAINT MONO (-890 3860);
DISPLAY INVISIBLE (-890 3860);
FORCEPROP 1 LASTPIN (-900 3850) BN 18
J 2
(-888 3858);
DISPLAY 0.680851 (-888 3858);
PAINT GREEN (-888 3858);
FORCEPROP 2 LAST CDS_LIB standard
J 0
(-950 3850);
DISPLAY INVISIBLE (-950 3850);
FORCEPROP 1 LAST BODY_TYPE PLUMBING
J 2
(-950 3900);
DISPLAY 0.872340 (-950 3900);
PAINT GREEN (-950 3900);
DISPLAY INVISIBLE (-950 3900);
FORCEPROP 1 LAST HDL_TAP TRUE
J 2
(-1275 3725);
DISPLAY 0.872340 (-1275 3725);
DISPLAY INVISIBLE (-1275 3725);
FORCEPROP 1 LAST PATH I79
J 2
(-948 3850);
DISPLAY 0.872340 (-948 3850);
PAINT GREEN (-948 3850);
DISPLAY INVISIBLE (-948 3850);
FORCEADD TAP..1
R 2
(-950 450);
FORCEPROP 3 LASTPIN (-900 450) SIG_NAME M_H_CPU0_CLK_DP<1>
J 0
(-890 460);
DISPLAY 0.659574 (-890 460);
PAINT MONO (-890 460);
DISPLAY INVISIBLE (-890 460);
FORCEPROP 1 LASTPIN (-900 450) BN 1
J 2
(-888 458);
DISPLAY 0.680851 (-888 458);
PAINT GREEN (-888 458);
FORCEPROP 2 LAST CDS_LIB standard
J 0
(-950 450);
DISPLAY INVISIBLE (-950 450);
FORCEPROP 1 LAST BODY_TYPE PLUMBING
J 2
(-950 500);
DISPLAY 0.872340 (-950 500);
PAINT GREEN (-950 500);
DISPLAY INVISIBLE (-950 500);
FORCEPROP 1 LAST HDL_TAP TRUE
J 2
(-1275 325);
DISPLAY 0.872340 (-1275 325);
DISPLAY INVISIBLE (-1275 325);
FORCEPROP 1 LAST PATH I8
J 2
(-948 450);
DISPLAY 0.872340 (-948 450);
PAINT GREEN (-948 450);
DISPLAY INVISIBLE (-948 450);
FORCEADD TAP..1
R 2
(-950 4050);
FORCEPROP 3 LASTPIN (-900 4050) SIG_NAME M_H_CPU0_SA_DQ<22>
J 0
(-890 4060);
DISPLAY 0.659574 (-890 4060);
PAINT MONO (-890 4060);
DISPLAY INVISIBLE (-890 4060);
FORCEPROP 1 LASTPIN (-900 4050) BN 22
J 2
(-888 4058);
DISPLAY 0.680851 (-888 4058);
PAINT GREEN (-888 4058);
FORCEPROP 2 LAST CDS_LIB standard
J 0
(-950 4050);
DISPLAY INVISIBLE (-950 4050);
FORCEPROP 1 LAST BODY_TYPE PLUMBING
J 2
(-950 4100);
DISPLAY 0.872340 (-950 4100);
PAINT GREEN (-950 4100);
DISPLAY INVISIBLE (-950 4100);
FORCEPROP 1 LAST HDL_TAP TRUE
J 2
(-1275 3925);
DISPLAY 0.872340 (-1275 3925);
DISPLAY INVISIBLE (-1275 3925);
FORCEPROP 1 LAST PATH I80
J 2
(-948 4050);
DISPLAY 0.872340 (-948 4050);
PAINT GREEN (-948 4050);
DISPLAY INVISIBLE (-948 4050);
FORCEADD TAP..1
R 2
(-950 4000);
FORCEPROP 3 LASTPIN (-900 4000) SIG_NAME M_H_CPU0_SA_DQ<21>
J 0
(-890 4010);
DISPLAY 0.659574 (-890 4010);
PAINT MONO (-890 4010);
DISPLAY INVISIBLE (-890 4010);
FORCEPROP 1 LASTPIN (-900 4000) BN 21
J 2
(-888 4008);
DISPLAY 0.680851 (-888 4008);
PAINT GREEN (-888 4008);
FORCEPROP 2 LAST CDS_LIB standard
J 0
(-950 4000);
DISPLAY INVISIBLE (-950 4000);
FORCEPROP 1 LAST BODY_TYPE PLUMBING
J 2
(-950 4050);
DISPLAY 0.872340 (-950 4050);
PAINT GREEN (-950 4050);
DISPLAY INVISIBLE (-950 4050);
FORCEPROP 1 LAST HDL_TAP TRUE
J 2
(-1275 3875);
DISPLAY 0.872340 (-1275 3875);
DISPLAY INVISIBLE (-1275 3875);
FORCEPROP 1 LAST PATH I81
J 2
(-948 4000);
DISPLAY 0.872340 (-948 4000);
PAINT GREEN (-948 4000);
DISPLAY INVISIBLE (-948 4000);
FORCEADD TAP..1
R 2
(-950 4150);
FORCEPROP 3 LASTPIN (-900 4150) SIG_NAME M_H_CPU0_SA_DQ<24>
J 0
(-890 4160);
DISPLAY 0.659574 (-890 4160);
PAINT MONO (-890 4160);
DISPLAY INVISIBLE (-890 4160);
FORCEPROP 1 LASTPIN (-900 4150) BN 24
J 2
(-888 4158);
DISPLAY 0.680851 (-888 4158);
PAINT GREEN (-888 4158);
FORCEPROP 2 LAST CDS_LIB standard
J 0
(-950 4150);
DISPLAY INVISIBLE (-950 4150);
FORCEPROP 1 LAST BODY_TYPE PLUMBING
J 2
(-950 4200);
DISPLAY 0.872340 (-950 4200);
PAINT GREEN (-950 4200);
DISPLAY INVISIBLE (-950 4200);
FORCEPROP 1 LAST HDL_TAP TRUE
J 2
(-1275 4025);
DISPLAY 0.872340 (-1275 4025);
DISPLAY INVISIBLE (-1275 4025);
FORCEPROP 1 LAST PATH I82
J 2
(-948 4150);
DISPLAY 0.872340 (-948 4150);
PAINT GREEN (-948 4150);
DISPLAY INVISIBLE (-948 4150);
FORCEADD TAP..1
R 2
(-950 4100);
FORCEPROP 3 LASTPIN (-900 4100) SIG_NAME M_H_CPU0_SA_DQ<23>
J 0
(-890 4110);
DISPLAY 0.659574 (-890 4110);
PAINT MONO (-890 4110);
DISPLAY INVISIBLE (-890 4110);
FORCEPROP 1 LASTPIN (-900 4100) BN 23
J 2
(-888 4108);
DISPLAY 0.680851 (-888 4108);
PAINT GREEN (-888 4108);
FORCEPROP 2 LAST CDS_LIB standard
J 0
(-950 4100);
DISPLAY INVISIBLE (-950 4100);
FORCEPROP 1 LAST BODY_TYPE PLUMBING
J 2
(-950 4150);
DISPLAY 0.872340 (-950 4150);
PAINT GREEN (-950 4150);
DISPLAY INVISIBLE (-950 4150);
FORCEPROP 1 LAST HDL_TAP TRUE
J 2
(-1275 3975);
DISPLAY 0.872340 (-1275 3975);
DISPLAY INVISIBLE (-1275 3975);
FORCEPROP 1 LAST PATH I83
J 2
(-948 4100);
DISPLAY 0.872340 (-948 4100);
PAINT GREEN (-948 4100);
DISPLAY INVISIBLE (-948 4100);
FORCEADD TAP..1
R 2
(-950 4200);
FORCEPROP 3 LASTPIN (-900 4200) SIG_NAME M_H_CPU0_SA_DQ<25>
J 0
(-890 4210);
DISPLAY 0.659574 (-890 4210);
PAINT MONO (-890 4210);
DISPLAY INVISIBLE (-890 4210);
FORCEPROP 1 LASTPIN (-900 4200) BN 25
J 2
(-888 4208);
DISPLAY 0.680851 (-888 4208);
PAINT GREEN (-888 4208);
FORCEPROP 2 LAST CDS_LIB standard
J 0
(-950 4200);
DISPLAY INVISIBLE (-950 4200);
FORCEPROP 1 LAST BODY_TYPE PLUMBING
J 2
(-950 4250);
DISPLAY 0.872340 (-950 4250);
PAINT GREEN (-950 4250);
DISPLAY INVISIBLE (-950 4250);
FORCEPROP 1 LAST HDL_TAP TRUE
J 2
(-1275 4075);
DISPLAY 0.872340 (-1275 4075);
DISPLAY INVISIBLE (-1275 4075);
FORCEPROP 1 LAST PATH I84
J 2
(-948 4200);
DISPLAY 0.872340 (-948 4200);
PAINT GREEN (-948 4200);
DISPLAY INVISIBLE (-948 4200);
FORCEADD TAP..1
R 2
(-950 4300);
FORCEPROP 3 LASTPIN (-900 4300) SIG_NAME M_H_CPU0_SA_DQ<27>
J 0
(-890 4310);
DISPLAY 0.659574 (-890 4310);
PAINT MONO (-890 4310);
DISPLAY INVISIBLE (-890 4310);
FORCEPROP 1 LASTPIN (-900 4300) BN 27
J 2
(-888 4308);
DISPLAY 0.680851 (-888 4308);
PAINT GREEN (-888 4308);
FORCEPROP 2 LAST CDS_LIB standard
J 0
(-950 4300);
DISPLAY INVISIBLE (-950 4300);
FORCEPROP 1 LAST BODY_TYPE PLUMBING
J 2
(-950 4350);
DISPLAY 0.872340 (-950 4350);
PAINT GREEN (-950 4350);
DISPLAY INVISIBLE (-950 4350);
FORCEPROP 1 LAST HDL_TAP TRUE
J 2
(-1275 4175);
DISPLAY 0.872340 (-1275 4175);
DISPLAY INVISIBLE (-1275 4175);
FORCEPROP 1 LAST PATH I85
J 2
(-948 4300);
DISPLAY 0.872340 (-948 4300);
PAINT GREEN (-948 4300);
DISPLAY INVISIBLE (-948 4300);
FORCEADD TAP..1
R 2
(-950 4250);
FORCEPROP 3 LASTPIN (-900 4250) SIG_NAME M_H_CPU0_SA_DQ<26>
J 0
(-890 4260);
DISPLAY 0.659574 (-890 4260);
PAINT MONO (-890 4260);
DISPLAY INVISIBLE (-890 4260);
FORCEPROP 1 LASTPIN (-900 4250) BN 26
J 2
(-888 4258);
DISPLAY 0.680851 (-888 4258);
PAINT GREEN (-888 4258);
FORCEPROP 2 LAST CDS_LIB standard
J 0
(-950 4250);
DISPLAY INVISIBLE (-950 4250);
FORCEPROP 1 LAST BODY_TYPE PLUMBING
J 2
(-950 4300);
DISPLAY 0.872340 (-950 4300);
PAINT GREEN (-950 4300);
DISPLAY INVISIBLE (-950 4300);
FORCEPROP 1 LAST HDL_TAP TRUE
J 2
(-1275 4125);
DISPLAY 0.872340 (-1275 4125);
DISPLAY INVISIBLE (-1275 4125);
FORCEPROP 1 LAST PATH I86
J 2
(-948 4250);
DISPLAY 0.872340 (-948 4250);
PAINT GREEN (-948 4250);
DISPLAY INVISIBLE (-948 4250);
FORCEADD TAP..1
R 2
(-950 4350);
FORCEPROP 3 LASTPIN (-900 4350) SIG_NAME M_H_CPU0_SA_DQ<28>
J 0
(-890 4360);
DISPLAY 0.659574 (-890 4360);
PAINT MONO (-890 4360);
DISPLAY INVISIBLE (-890 4360);
FORCEPROP 1 LASTPIN (-900 4350) BN 28
J 2
(-888 4358);
DISPLAY 0.680851 (-888 4358);
PAINT GREEN (-888 4358);
FORCEPROP 2 LAST CDS_LIB standard
J 0
(-950 4350);
DISPLAY INVISIBLE (-950 4350);
FORCEPROP 1 LAST BODY_TYPE PLUMBING
J 2
(-950 4400);
DISPLAY 0.872340 (-950 4400);
PAINT GREEN (-950 4400);
DISPLAY INVISIBLE (-950 4400);
FORCEPROP 1 LAST HDL_TAP TRUE
J 2
(-1275 4225);
DISPLAY 0.872340 (-1275 4225);
DISPLAY INVISIBLE (-1275 4225);
FORCEPROP 1 LAST PATH I87
J 2
(-948 4350);
DISPLAY 0.872340 (-948 4350);
PAINT GREEN (-948 4350);
DISPLAY INVISIBLE (-948 4350);
FORCEADD TAP..1
R 2
(-950 4400);
FORCEPROP 3 LASTPIN (-900 4400) SIG_NAME M_H_CPU0_SA_DQ<29>
J 0
(-890 4410);
DISPLAY 0.659574 (-890 4410);
PAINT MONO (-890 4410);
DISPLAY INVISIBLE (-890 4410);
FORCEPROP 1 LASTPIN (-900 4400) BN 29
J 2
(-888 4408);
DISPLAY 0.680851 (-888 4408);
PAINT GREEN (-888 4408);
FORCEPROP 2 LAST CDS_LIB standard
J 0
(-950 4400);
DISPLAY INVISIBLE (-950 4400);
FORCEPROP 1 LAST BODY_TYPE PLUMBING
J 2
(-950 4450);
DISPLAY 0.872340 (-950 4450);
PAINT GREEN (-950 4450);
DISPLAY INVISIBLE (-950 4450);
FORCEPROP 1 LAST HDL_TAP TRUE
J 2
(-1275 4275);
DISPLAY 0.872340 (-1275 4275);
DISPLAY INVISIBLE (-1275 4275);
FORCEPROP 1 LAST PATH I88
J 2
(-948 4400);
DISPLAY 0.872340 (-948 4400);
PAINT GREEN (-948 4400);
DISPLAY INVISIBLE (-948 4400);
FORCEADD TAP..1
R 2
(-950 4450);
FORCEPROP 3 LASTPIN (-900 4450) SIG_NAME M_H_CPU0_SA_DQ<30>
J 0
(-890 4460);
DISPLAY 0.659574 (-890 4460);
PAINT MONO (-890 4460);
DISPLAY INVISIBLE (-890 4460);
FORCEPROP 1 LASTPIN (-900 4450) BN 30
J 2
(-888 4458);
DISPLAY 0.680851 (-888 4458);
PAINT GREEN (-888 4458);
FORCEPROP 2 LAST CDS_LIB standard
J 0
(-950 4450);
DISPLAY INVISIBLE (-950 4450);
FORCEPROP 1 LAST BODY_TYPE PLUMBING
J 2
(-950 4500);
DISPLAY 0.872340 (-950 4500);
PAINT GREEN (-950 4500);
DISPLAY INVISIBLE (-950 4500);
FORCEPROP 1 LAST HDL_TAP TRUE
J 2
(-1275 4325);
DISPLAY 0.872340 (-1275 4325);
DISPLAY INVISIBLE (-1275 4325);
FORCEPROP 1 LAST PATH I89
J 2
(-948 4450);
DISPLAY 0.872340 (-948 4450);
PAINT GREEN (-948 4450);
DISPLAY INVISIBLE (-948 4450);
FORCEADD TAP..1
R 2
(-950 650);
FORCEPROP 3 LASTPIN (-900 650) SIG_NAME M_H_CPU0_SB_CB<2>
J 0
(-890 660);
DISPLAY 0.659574 (-890 660);
PAINT MONO (-890 660);
DISPLAY INVISIBLE (-890 660);
FORCEPROP 1 LASTPIN (-900 650) BN 2
J 2
(-888 658);
DISPLAY 0.680851 (-888 658);
PAINT GREEN (-888 658);
FORCEPROP 2 LAST CDS_LIB standard
J 0
(-950 650);
DISPLAY INVISIBLE (-950 650);
FORCEPROP 1 LAST BODY_TYPE PLUMBING
J 2
(-950 700);
DISPLAY 0.872340 (-950 700);
PAINT GREEN (-950 700);
DISPLAY INVISIBLE (-950 700);
FORCEPROP 1 LAST HDL_TAP TRUE
J 2
(-1275 525);
DISPLAY 0.872340 (-1275 525);
DISPLAY INVISIBLE (-1275 525);
FORCEPROP 1 LAST PATH I9
J 2
(-948 650);
DISPLAY 0.872340 (-948 650);
PAINT GREEN (-948 650);
DISPLAY INVISIBLE (-948 650);
FORCEADD TAP..1
R 2
(-950 4500);
FORCEPROP 3 LASTPIN (-900 4500) SIG_NAME M_H_CPU0_SA_DQ<31>
J 0
(-890 4510);
DISPLAY 0.659574 (-890 4510);
PAINT MONO (-890 4510);
DISPLAY INVISIBLE (-890 4510);
FORCEPROP 1 LASTPIN (-900 4500) BN 31
J 2
(-888 4508);
DISPLAY 0.680851 (-888 4508);
PAINT GREEN (-888 4508);
FORCEPROP 2 LAST CDS_LIB standard
J 0
(-950 4500);
DISPLAY INVISIBLE (-950 4500);
FORCEPROP 1 LAST BODY_TYPE PLUMBING
J 2
(-950 4550);
DISPLAY 0.872340 (-950 4550);
PAINT GREEN (-950 4550);
DISPLAY INVISIBLE (-950 4550);
FORCEPROP 1 LAST HDL_TAP TRUE
J 2
(-1275 4375);
DISPLAY 0.872340 (-1275 4375);
DISPLAY INVISIBLE (-1275 4375);
FORCEPROP 1 LAST PATH I90
J 2
(-948 4500);
DISPLAY 0.872340 (-948 4500);
PAINT GREEN (-948 4500);
DISPLAY INVISIBLE (-948 4500);
FORCEADD OFFPAGE..4
(3575 300);
FORCEPROP 2 LAST $XR1 97 
J 0
(3851 300);
DISPLAY 0.638298 (3851 300);
PAINT MONO (3851 300);
FORCEPROP 2 LAST $XR0 96 
J 0
(3761 300);
DISPLAY 0.638298 (3761 300);
PAINT MONO (3761 300);
FORCEPROP 2 LAST CDS_LIB standard
J 0
(3575 300);
PAINT MONO (3575 300);
DISPLAY INVISIBLE (3575 300);
FORCEPROP 1 LAST OFFPAGE TRUE
J 0
(3900 175);
DISPLAY 1.170213 (3900 175);
PAINT GREEN (3900 175);
DISPLAY INVISIBLE (3900 175);
FORCEPROP 1 LAST COMMENT_BODY TRUE
J 0
(3550 200);
DISPLAY 1.170213 (3550 200);
PAINT GREEN (3550 200);
DISPLAY INVISIBLE (3550 200);
FORCEPROP 2 LAST PATH I92
J 0
(3750 375);
DISPLAY 1.021277 (3750 375);
DISPLAY INVISIBLE (3750 375);
FORCEADD OFFPAGE..4
(3575 400);
FORCEPROP 2 LAST $XR0 96 
J 0
(3761 400);
DISPLAY 0.638298 (3761 400);
PAINT MONO (3761 400);
FORCEPROP 2 LAST CDS_LIB standard
J 0
(3575 400);
PAINT MONO (3575 400);
DISPLAY INVISIBLE (3575 400);
FORCEPROP 1 LAST OFFPAGE TRUE
J 0
(3900 275);
DISPLAY 1.170213 (3900 275);
PAINT GREEN (3900 275);
DISPLAY INVISIBLE (3900 275);
FORCEPROP 1 LAST COMMENT_BODY TRUE
J 0
(3550 300);
DISPLAY 1.170213 (3550 300);
PAINT GREEN (3550 300);
DISPLAY INVISIBLE (3550 300);
FORCEPROP 2 LAST PATH I93
J 0
(3750 475);
DISPLAY 1.021277 (3750 475);
DISPLAY INVISIBLE (3750 475);
FORCEADD OFFPAGE..4
(3575 450);
FORCEPROP 2 LAST $XR0 97 
J 0
(3761 450);
DISPLAY 0.638298 (3761 450);
PAINT MONO (3761 450);
FORCEPROP 2 LAST CDS_LIB standard
J 0
(3575 450);
PAINT MONO (3575 450);
DISPLAY INVISIBLE (3575 450);
FORCEPROP 1 LAST OFFPAGE TRUE
J 0
(3900 325);
DISPLAY 1.170213 (3900 325);
PAINT GREEN (3900 325);
DISPLAY INVISIBLE (3900 325);
FORCEPROP 1 LAST COMMENT_BODY TRUE
J 0
(3550 350);
DISPLAY 1.170213 (3550 350);
PAINT GREEN (3550 350);
DISPLAY INVISIBLE (3550 350);
FORCEPROP 2 LAST PATH I94
J 0
(3750 525);
DISPLAY 1.021277 (3750 525);
DISPLAY INVISIBLE (3750 525);
FORCEADD OFFPAGE..4
(3575 550);
FORCEPROP 2 LAST $XR0 96 
J 0
(3761 550);
DISPLAY 0.638298 (3761 550);
PAINT MONO (3761 550);
FORCEPROP 2 LAST CDS_LIB standard
J 0
(3575 550);
PAINT MONO (3575 550);
DISPLAY INVISIBLE (3575 550);
FORCEPROP 1 LAST OFFPAGE TRUE
J 0
(3900 425);
DISPLAY 1.170213 (3900 425);
PAINT GREEN (3900 425);
DISPLAY INVISIBLE (3900 425);
FORCEPROP 1 LAST COMMENT_BODY TRUE
J 0
(3550 450);
DISPLAY 1.170213 (3550 450);
PAINT GREEN (3550 450);
DISPLAY INVISIBLE (3550 450);
FORCEPROP 2 LAST PATH I95
J 0
(3750 625);
DISPLAY 1.021277 (3750 625);
DISPLAY INVISIBLE (3750 625);
FORCEADD OFFPAGE..4
(3575 600);
FORCEPROP 2 LAST $XR0 97 
J 0
(3761 600);
DISPLAY 0.638298 (3761 600);
PAINT MONO (3761 600);
FORCEPROP 2 LAST CDS_LIB standard
J 0
(3575 600);
PAINT MONO (3575 600);
DISPLAY INVISIBLE (3575 600);
FORCEPROP 1 LAST OFFPAGE TRUE
J 0
(3900 475);
DISPLAY 1.170213 (3900 475);
PAINT GREEN (3900 475);
DISPLAY INVISIBLE (3900 475);
FORCEPROP 1 LAST COMMENT_BODY TRUE
J 0
(3550 500);
DISPLAY 1.170213 (3550 500);
PAINT GREEN (3550 500);
DISPLAY INVISIBLE (3550 500);
FORCEPROP 2 LAST PATH I96
J 0
(3750 675);
DISPLAY 1.021277 (3750 675);
DISPLAY INVISIBLE (3750 675);
FORCEADD TAP..1
(2475 750);
FORCEPROP 3 LASTPIN (2425 750) SIG_NAME M_H_CPU0_SB_CS_N<0>
J 0
(2435 760);
DISPLAY 0.659574 (2435 760);
PAINT MONO (2435 760);
DISPLAY INVISIBLE (2435 760);
FORCEPROP 1 LASTPIN (2425 750) BN 0
J 0
(2413 758);
DISPLAY 0.680851 (2413 758);
PAINT GREEN (2413 758);
FORCEPROP 2 LAST CDS_LIB standard
J 0
(2475 750);
DISPLAY INVISIBLE (2475 750);
FORCEPROP 1 LAST BODY_TYPE PLUMBING
J 0
(2475 800);
DISPLAY 0.872340 (2475 800);
PAINT GREEN (2475 800);
DISPLAY INVISIBLE (2475 800);
FORCEPROP 1 LAST HDL_TAP TRUE
J 0
(2800 625);
DISPLAY 0.872340 (2800 625);
DISPLAY INVISIBLE (2800 625);
FORCEPROP 1 LAST PATH I97
J 0
(2473 750);
DISPLAY 0.872340 (2473 750);
PAINT GREEN (2473 750);
DISPLAY INVISIBLE (2473 750);
FORCEADD TAP..1
(2475 900);
FORCEPROP 3 LASTPIN (2425 900) SIG_NAME M_H_CPU0_SB_CS_N<3>
J 0
(2435 910);
DISPLAY 0.659574 (2435 910);
PAINT MONO (2435 910);
DISPLAY INVISIBLE (2435 910);
FORCEPROP 1 LASTPIN (2425 900) BN 3
J 0
(2413 908);
DISPLAY 0.680851 (2413 908);
PAINT GREEN (2413 908);
FORCEPROP 2 LAST CDS_LIB standard
J 0
(2475 900);
DISPLAY INVISIBLE (2475 900);
FORCEPROP 1 LAST BODY_TYPE PLUMBING
J 0
(2475 950);
DISPLAY 0.872340 (2475 950);
PAINT GREEN (2475 950);
DISPLAY INVISIBLE (2475 950);
FORCEPROP 1 LAST HDL_TAP TRUE
J 0
(2800 775);
DISPLAY 0.872340 (2800 775);
DISPLAY INVISIBLE (2800 775);
FORCEPROP 1 LAST PATH I98
J 0
(2473 900);
DISPLAY 0.872340 (2473 900);
PAINT GREEN (2473 900);
DISPLAY INVISIBLE (2473 900);
FORCEADD TAP..1
(2475 800);
FORCEPROP 3 LASTPIN (2425 800) SIG_NAME M_H_CPU0_SB_CS_N<1>
J 0
(2435 810);
DISPLAY 0.659574 (2435 810);
PAINT MONO (2435 810);
DISPLAY INVISIBLE (2435 810);
FORCEPROP 1 LASTPIN (2425 800) BN 1
J 0
(2413 808);
DISPLAY 0.680851 (2413 808);
PAINT GREEN (2413 808);
FORCEPROP 2 LAST CDS_LIB standard
J 0
(2475 800);
DISPLAY INVISIBLE (2475 800);
FORCEPROP 1 LAST BODY_TYPE PLUMBING
J 0
(2475 850);
DISPLAY 0.872340 (2475 850);
PAINT GREEN (2475 850);
DISPLAY INVISIBLE (2475 850);
FORCEPROP 1 LAST HDL_TAP TRUE
J 0
(2800 675);
DISPLAY 0.872340 (2800 675);
DISPLAY INVISIBLE (2800 675);
FORCEPROP 1 LAST PATH I99
J 0
(2473 800);
DISPLAY 0.872340 (2473 800);
PAINT GREEN (2473 800);
DISPLAY INVISIBLE (2473 800);
FORCEADD QUANTA_TITLE_BLOCK_C..1
(5400 -1000);
FORCEPROP 0 LAST CDS_CON_LAST_MODIFIED Fri Aug 25 14:00:12 2023
J 0
(3515 -985);
PAINT MONO (3515 -985);
DISPLAY INVISIBLE (3515 -985);
FORCEPROP 1 LAST CUSTOM_TXT_CDS <CON_LAST_MODIFIED>
J 0
(3515 -985);
DISPLAY 0.978723 (3515 -985);
FORCEPROP 2 LAST CUSTOM_TXT_CDS <XR_PAGE_TITLE>
J 0
(-2490 4250);
DISPLAY 0.638298 (-2490 4250);
PAINT PINK (-2490 4250);
DISPLAY INVISIBLE (-2490 4250);
FORCEPROP 2 LAST CUSTOM_TXT_CDS <Q_NUMBER>
J 0
(3997 -897);
DISPLAY 1.212766 (3997 -897);
FORCEPROP 1 LAST CUSTOM_TXT_CDS <NAME_2>
J 0
(2225 -950);
FORCEPROP 1 LAST CUSTOM_TXT_CDS <NAME_1>
J 0
(2225 -825);
FORCEPROP 1 LAST CUSTOM_TXT_CDS <Q_PROJ>
J 0
(3018 -898);
DISPLAY 1.212766 (3018 -898);
FORCEPROP 1 LAST CUSTOM_TXT_CDS <Q_REV>
J 0
(5216 -897);
DISPLAY 1.212766 (5216 -897);
FORCEPROP 1 LAST CUSTOM_TXT_CDS <CON_PAGE_NUM> OF <CON_TOTAL_PAGES>
J 0
(4954 -982);
DISPLAY 0.978723 (4954 -982);
FORCEPROP 1 LAST Q_TITLE SPR CPU0 - DDR CH H (15 OF 30)
J 0
(-3966 -974);
DISPLAY 1.957447 (-3966 -974);
PAINT GREEN (-3966 -974);
FORCEPROP 1 LAST Q_DEPT 
J 1
(1637 -951);
DISPLAY 1.957447 (1637 -951);
PAINT GREEN (1637 -951);
FORCEPROP 2 LAST CDS_LIB pure_quanta
J 0
(5400 -1000);
PAINT MONO (5400 -1000);
DISPLAY INVISIBLE (5400 -1000);
FORCEPROP 1 LAST CDS_LMAN_SYM_OUTLINE -9475,6775,100,-125
J 0
(5400 -1000);
DISPLAY 0.468085 (5400 -1000);
PAINT GREEN (5400 -1000);
DISPLAY INVISIBLE (5400 -1000);
FORCEPROP 2 LAST PAGE_BORDER TRUE
J 0
(-2490 4250);
DISPLAY 0.638298 (-2490 4250);
PAINT PINK (-2490 4250);
DISPLAY INVISIBLE (-2490 4250);
FORCEPROP 2 LAST CDS_XR_PAGE_TITLE CR-27 : @S9S_MB_2U_LIB.S9S_MB_2U(SCH_1):PAGE27
J 0
(-2490 4250);
DISPLAY 0.638298 (-2490 4250);
PAINT PINK (-2490 4250);
DISPLAY INVISIBLE (-2490 4250);
FORCEPROP 1 LAST COMMENT_BODY TRUE
J 0
(5412 -1013);
DISPLAY 0.978723 (5412 -1013);
PAINT GREEN (5412 -1013);
DISPLAY INVISIBLE (5412 -1013);
WIRE 17 -1 (2525 2175)(2525 2225);
WIRE 17 -1 (2525 2125)(2525 2175);
WIRE 17 -1 (2525 2225)(3525 2225);
FORCEPROP 2 LAST SIG_NAME M_H_CPU0_SA_CA<6:0>
J 0
(2665 2235);
DISPLAY 0.680851 (2665 2235);
PAINT WHITE (2665 2235);
WIRE 17 -1 (2525 2075)(2525 2125);
WIRE 17 -1 (2525 2025)(2525 2075);
WIRE 17 -1 (2525 1975)(2525 2025);
WIRE 17 -1 (2525 1925)(2525 1975);
WIRE 17 -1 (2525 1175)(2525 1225);
WIRE 17 -1 (2525 1125)(2525 1175);
WIRE 17 -1 (2525 1225)(3525 1225);
FORCEPROP 2 LAST SIG_NAME M_H_CPU0_SA_CS_N<3:0>
J 0
(2665 1235);
DISPLAY 0.680851 (2665 1235);
PAINT WHITE (2665 1235);
WIRE 17 -1 (2525 1075)(2525 1125);
WIRE 17 -1 (2525 3925)(2525 3975);
WIRE 17 -1 (2525 3875)(2525 3925);
WIRE 17 -1 (2525 3975)(3525 3975);
FORCEPROP 2 LAST SIG_NAME M_H_CPU0_SA_DQS_DN<9:0>
J 0
(2665 3985);
DISPLAY 0.680851 (2665 3985);
PAINT WHITE (2665 3985);
WIRE 17 -1 (2525 3825)(2525 3875);
WIRE 17 -1 (2525 3775)(2525 3825);
WIRE 17 -1 (2525 3725)(2525 3775);
WIRE 17 -1 (2525 3675)(2525 3725);
WIRE 17 -1 (2525 3625)(2525 3675);
WIRE 17 -1 (2525 3575)(2525 3625);
WIRE 17 -1 (2525 3525)(2525 3575);
WIRE 17 -1 (2525 4475)(2525 4525);
WIRE 17 -1 (2525 4425)(2525 4475);
WIRE 17 -1 (2525 4525)(3525 4525);
FORCEPROP 2 LAST SIG_NAME M_H_CPU0_SA_DQS_DP<9:0>
J 0
(2665 4535);
DISPLAY 0.680851 (2665 4535);
PAINT WHITE (2665 4535);
WIRE 17 -1 (2525 4375)(2525 4425);
WIRE 17 -1 (2525 4325)(2525 4375);
WIRE 17 -1 (2525 4275)(2525 4325);
WIRE 17 -1 (2525 4225)(2525 4275);
WIRE 17 -1 (2525 4175)(2525 4225);
WIRE 17 -1 (2525 4125)(2525 4175);
WIRE 17 -1 (2525 4075)(2525 4125);
WIRE 17 -1 (2525 1675)(2525 1725);
WIRE 17 -1 (2525 1625)(2525 1675);
WIRE 17 -1 (2525 1725)(3525 1725);
FORCEPROP 2 LAST SIG_NAME M_H_CPU0_SB_CA<6:0>
J 0
(2665 1735);
DISPLAY 0.680851 (2665 1735);
PAINT WHITE (2665 1735);
WIRE 17 -1 (2525 1575)(2525 1625);
WIRE 17 -1 (2525 1525)(2525 1575);
WIRE 17 -1 (2525 1475)(2525 1525);
WIRE 17 -1 (2525 1425)(2525 1475);
WIRE 17 -1 (2525 875)(2525 925);
WIRE 17 -1 (2525 825)(2525 875);
WIRE 17 -1 (2525 925)(3525 925);
FORCEPROP 2 LAST SIG_NAME M_H_CPU0_SB_CS_N<3:0>
J 0
(2665 935);
DISPLAY 0.680851 (2665 935);
PAINT WHITE (2665 935);
WIRE 17 -1 (2525 775)(2525 825);
WIRE 17 -1 (2525 2775)(2525 2825);
WIRE 17 -1 (2525 2725)(2525 2775);
WIRE 17 -1 (2525 2825)(3525 2825);
FORCEPROP 2 LAST SIG_NAME M_H_CPU0_SB_DQS_DN<9:0>
J 0
(2665 2835);
DISPLAY 0.680851 (2665 2835);
PAINT WHITE (2665 2835);
WIRE 17 -1 (2525 2675)(2525 2725);
WIRE 17 -1 (2525 2625)(2525 2675);
WIRE 17 -1 (2525 2575)(2525 2625);
WIRE 17 -1 (2525 2525)(2525 2575);
WIRE 17 -1 (2525 2475)(2525 2525);
WIRE 17 -1 (2525 2425)(2525 2475);
WIRE 17 -1 (2525 2375)(2525 2425);
WIRE 17 -1 (2525 3325)(2525 3375);
WIRE 17 -1 (2525 3275)(2525 3325);
WIRE 17 -1 (2525 3375)(3525 3375);
FORCEPROP 2 LAST SIG_NAME M_H_CPU0_SB_DQS_DP<9:0>
J 0
(2665 3385);
DISPLAY 0.680851 (2665 3385);
PAINT WHITE (2665 3385);
WIRE 17 -1 (2525 3225)(2525 3275);
WIRE 17 -1 (2525 3175)(2525 3225);
WIRE 17 -1 (2525 3125)(2525 3175);
WIRE 17 -1 (2525 3075)(2525 3125);
WIRE 17 -1 (2525 3025)(2525 3075);
WIRE 17 -1 (2525 2975)(2525 3025);
WIRE 17 -1 (2525 2925)(2525 2975);
WIRE 17 -1 (-1000 575)(-1000 625);
WIRE 17 -1 (-1000 625)(-1000 675);
WIRE 17 -1 (-1000 675)(-1000 725);
WIRE 17 -1 (-1000 725)(-1000 775);
WIRE 17 -1 (-1000 775)(-1000 825);
WIRE 17 -1 (-1000 825)(-1000 875);
WIRE 17 -1 (-1000 875)(-1000 925);
WIRE 17 -1 (-1925 925)(-1000 925);
FORCEPROP 2 LAST SIG_NAME M_H_CPU0_SB_CB<7:0>
J 0
(-1785 935);
DISPLAY 0.680851 (-1785 935);
PAINT WHITE (-1785 935);
WIRE 17 -1 (-1000 975)(-1000 1025);
WIRE 17 -1 (-1000 1025)(-1000 1075);
WIRE 17 -1 (-1000 1075)(-1000 1125);
WIRE 17 -1 (-1000 1125)(-1000 1175);
WIRE 17 -1 (-1000 1175)(-1000 1225);
WIRE 17 -1 (-1000 1225)(-1000 1275);
WIRE 17 -1 (-1000 1275)(-1000 1325);
WIRE 17 -1 (-1000 1325)(-1000 1375);
WIRE 17 -1 (-1000 1375)(-1000 1425);
WIRE 17 -1 (-1000 1425)(-1000 1475);
WIRE 17 -1 (-1000 1475)(-1000 1525);
WIRE 17 -1 (-1000 1525)(-1000 1575);
WIRE 17 -1 (-1000 1575)(-1000 1625);
WIRE 17 -1 (-1000 1625)(-1000 1675);
WIRE 17 -1 (-1000 1675)(-1000 1725);
WIRE 17 -1 (-1000 1725)(-1000 1775);
WIRE 17 -1 (-1000 1775)(-1000 1825);
WIRE 17 -1 (-1000 1825)(-1000 1875);
WIRE 17 -1 (-1000 1875)(-1000 1925);
WIRE 17 -1 (-1000 1925)(-1000 1975);
WIRE 17 -1 (-1000 1975)(-1000 2025);
WIRE 17 -1 (-1000 2025)(-1000 2075);
WIRE 17 -1 (-1000 2075)(-1000 2125);
WIRE 17 -1 (-1000 2125)(-1000 2175);
WIRE 17 -1 (-1000 2175)(-1000 2225);
WIRE 17 -1 (-1000 2225)(-1000 2275);
WIRE 17 -1 (-1000 2275)(-1000 2325);
WIRE 17 -1 (-1000 2325)(-1000 2375);
WIRE 17 -1 (-1000 2375)(-1000 2425);
WIRE 17 -1 (-1000 2425)(-1000 2475);
WIRE 17 -1 (-1000 2475)(-1000 2525);
WIRE 17 -1 (-1925 2525)(-1000 2525);
FORCEPROP 2 LAST SIG_NAME M_H_CPU0_SB_DQ<31:0>
J 0
(-1785 2535);
DISPLAY 0.680851 (-1785 2535);
PAINT WHITE (-1785 2535);
WIRE 17 -1 (-1000 2575)(-1000 2625);
WIRE 17 -1 (-1000 2625)(-1000 2675);
WIRE 17 -1 (-1000 2675)(-1000 2725);
WIRE 17 -1 (-1000 2725)(-1000 2775);
WIRE 17 -1 (-1000 2775)(-1000 2825);
WIRE 17 -1 (-1000 2825)(-1000 2875);
WIRE 17 -1 (-1000 2875)(-1000 2925);
WIRE 17 -1 (-1925 2925)(-1000 2925);
FORCEPROP 2 LAST SIG_NAME M_H_CPU0_SA_CB<7:0>
J 0
(-1785 2935);
DISPLAY 0.680851 (-1785 2935);
PAINT WHITE (-1785 2935);
WIRE 17 -1 (-1000 2975)(-1000 3025);
WIRE 17 -1 (-1000 3025)(-1000 3075);
WIRE 17 -1 (-1000 3075)(-1000 3125);
WIRE 17 -1 (-1000 3125)(-1000 3175);
WIRE 17 -1 (-1000 3175)(-1000 3225);
WIRE 17 -1 (-1000 3225)(-1000 3275);
WIRE 17 -1 (-1000 3275)(-1000 3325);
WIRE 17 -1 (-1000 3325)(-1000 3375);
WIRE 17 -1 (-1000 3375)(-1000 3425);
WIRE 17 -1 (-1000 3425)(-1000 3475);
WIRE 17 -1 (-1000 3475)(-1000 3525);
WIRE 17 -1 (-1000 3525)(-1000 3575);
WIRE 17 -1 (-1000 3575)(-1000 3625);
WIRE 17 -1 (-1000 3625)(-1000 3675);
WIRE 17 -1 (-1000 3675)(-1000 3725);
WIRE 17 -1 (-1000 3725)(-1000 3775);
WIRE 17 -1 (-1000 3775)(-1000 3825);
WIRE 17 -1 (-1000 3825)(-1000 3875);
WIRE 17 -1 (-1000 3875)(-1000 3925);
WIRE 17 -1 (-1000 3925)(-1000 3975);
WIRE 17 -1 (-1000 3975)(-1000 4025);
WIRE 17 -1 (-1000 4025)(-1000 4075);
WIRE 17 -1 (-1000 4075)(-1000 4125);
WIRE 17 -1 (-1000 4125)(-1000 4175);
WIRE 17 -1 (-1000 4175)(-1000 4225);
WIRE 17 -1 (-1000 4225)(-1000 4275);
WIRE 17 -1 (-1000 4275)(-1000 4325);
WIRE 17 -1 (-1000 4325)(-1000 4375);
WIRE 17 -1 (-1000 4375)(-1000 4425);
WIRE 17 -1 (-1000 4425)(-1000 4475);
WIRE 17 -1 (-1000 4475)(-1000 4525);
WIRE 17 -1 (-1925 4525)(-1000 4525);
FORCEPROP 2 LAST SIG_NAME M_H_CPU0_SA_DQ<31:0>
J 0
(-1785 4535);
DISPLAY 0.680851 (-1785 4535);
PAINT WHITE (-1785 4535);
WIRE 17 -1 (-1000 425)(-1000 475);
WIRE 17 -1 (-1925 475)(-1000 475);
FORCEPROP 2 LAST SIG_NAME M_H_CPU0_CLK_DP<1:0>
J 0
(-1785 485);
DISPLAY 0.680851 (-1785 485);
PAINT WHITE (-1785 485);
WIRE 17 -1 (-1000 325)(-1000 375);
WIRE 17 -1 (-1925 375)(-1000 375);
FORCEPROP 2 LAST SIG_NAME M_H_CPU0_CLK_DN<1:0>
J 0
(-1785 385);
DISPLAY 0.680851 (-1785 385);
PAINT WHITE (-1785 385);
WIRE 16 -1 (-900 350)(-450 350);
WIRE 16 -1 (-900 300)(-450 300);
WIRE 16 -1 (-900 450)(-450 450);
WIRE 16 -1 (-900 400)(-450 400);
WIRE 16 -1 (-900 4500)(-450 4500);
WIRE 16 -1 (-900 4450)(-450 4450);
WIRE 16 -1 (-900 4400)(-450 4400);
WIRE 16 -1 (-900 4350)(-450 4350);
WIRE 16 -1 (-900 4300)(-450 4300);
WIRE 16 -1 (-900 4250)(-450 4250);
WIRE 16 -1 (-900 4200)(-450 4200);
WIRE 16 -1 (-900 4150)(-450 4150);
WIRE 16 -1 (-900 4100)(-450 4100);
WIRE 16 -1 (-900 4050)(-450 4050);
WIRE 16 -1 (-900 4000)(-450 4000);
WIRE 16 -1 (-900 3950)(-450 3950);
WIRE 16 -1 (-900 3900)(-450 3900);
WIRE 16 -1 (-900 3850)(-450 3850);
WIRE 16 -1 (-900 3800)(-450 3800);
WIRE 16 -1 (-900 3750)(-450 3750);
WIRE 16 -1 (-900 3700)(-450 3700);
WIRE 16 -1 (-900 3650)(-450 3650);
WIRE 16 -1 (-900 3600)(-450 3600);
WIRE 16 -1 (-900 3550)(-450 3550);
WIRE 16 -1 (-900 3500)(-450 3500);
WIRE 16 -1 (-900 3450)(-450 3450);
WIRE 16 -1 (-900 3400)(-450 3400);
WIRE 16 -1 (-900 3350)(-450 3350);
WIRE 16 -1 (-900 3300)(-450 3300);
WIRE 16 -1 (-900 3250)(-450 3250);
WIRE 16 -1 (-900 3200)(-450 3200);
WIRE 16 -1 (-900 3150)(-450 3150);
WIRE 16 -1 (-900 3100)(-450 3100);
WIRE 16 -1 (-900 3050)(-450 3050);
WIRE 16 -1 (-900 3000)(-450 3000);
WIRE 16 -1 (-900 2950)(-450 2950);
WIRE 16 -1 (-900 2900)(-450 2900);
WIRE 16 -1 (-900 2850)(-450 2850);
WIRE 16 -1 (-900 2800)(-450 2800);
WIRE 16 -1 (-900 2750)(-450 2750);
WIRE 16 -1 (-900 2700)(-450 2700);
WIRE 16 -1 (-900 2650)(-450 2650);
WIRE 16 -1 (-900 2600)(-450 2600);
WIRE 16 -1 (-900 2550)(-450 2550);
WIRE 16 -1 (-900 2500)(-450 2500);
WIRE 16 -1 (-900 2450)(-450 2450);
WIRE 16 -1 (-900 2400)(-450 2400);
WIRE 16 -1 (-900 2350)(-450 2350);
WIRE 16 -1 (-900 2300)(-450 2300);
WIRE 16 -1 (-900 2250)(-450 2250);
WIRE 16 -1 (-900 2200)(-450 2200);
WIRE 16 -1 (-900 2150)(-450 2150);
WIRE 16 -1 (-900 2100)(-450 2100);
WIRE 16 -1 (-900 2050)(-450 2050);
WIRE 16 -1 (-900 2000)(-450 2000);
WIRE 16 -1 (-900 1950)(-450 1950);
WIRE 16 -1 (-900 1900)(-450 1900);
WIRE 16 -1 (-900 1850)(-450 1850);
WIRE 16 -1 (-900 1800)(-450 1800);
WIRE 16 -1 (-900 1750)(-450 1750);
WIRE 16 -1 (-900 1700)(-450 1700);
WIRE 16 -1 (-900 1650)(-450 1650);
WIRE 16 -1 (-900 1600)(-450 1600);
WIRE 16 -1 (-900 1550)(-450 1550);
WIRE 16 -1 (-900 1500)(-450 1500);
WIRE 16 -1 (-900 1450)(-450 1450);
WIRE 16 -1 (-900 1400)(-450 1400);
WIRE 16 -1 (-900 1350)(-450 1350);
WIRE 16 -1 (-900 1300)(-450 1300);
WIRE 16 -1 (-900 1250)(-450 1250);
WIRE 16 -1 (-900 1200)(-450 1200);
WIRE 16 -1 (-900 1150)(-450 1150);
WIRE 16 -1 (-900 1100)(-450 1100);
WIRE 16 -1 (-900 1050)(-450 1050);
WIRE 16 -1 (-900 1000)(-450 1000);
WIRE 16 -1 (-900 950)(-450 950);
WIRE 16 -1 (-900 900)(-450 900);
WIRE 16 -1 (-900 850)(-450 850);
WIRE 16 -1 (-900 800)(-450 800);
WIRE 16 -1 (-900 750)(-450 750);
WIRE 16 -1 (-900 700)(-450 700);
WIRE 16 -1 (-900 650)(-450 650);
WIRE 16 -1 (-900 600)(-450 600);
WIRE 16 -1 (-900 550)(-450 550);
WIRE 16 -1 (3525 1350)(2000 1350);
FORCEPROP 2 LAST SIG_NAME M_H_CPU0_SB_PAR
J 0
(2634 1359);
DISPLAY 0.680851 (2634 1359);
PAINT WHITE (2634 1359);
WIRE 16 -1 (2000 2900)(2425 2900);
WIRE 16 -1 (2000 2950)(2425 2950);
WIRE 16 -1 (2000 3000)(2425 3000);
WIRE 16 -1 (2000 3050)(2425 3050);
WIRE 16 -1 (2000 3100)(2425 3100);
WIRE 16 -1 (2000 3150)(2425 3150);
WIRE 16 -1 (2000 3200)(2425 3200);
WIRE 16 -1 (2000 3250)(2425 3250);
WIRE 16 -1 (2000 3300)(2425 3300);
WIRE 16 -1 (2000 3350)(2425 3350);
WIRE 16 -1 (2000 2350)(2425 2350);
WIRE 16 -1 (2000 2400)(2425 2400);
WIRE 16 -1 (2000 2450)(2425 2450);
WIRE 16 -1 (2000 2500)(2425 2500);
WIRE 16 -1 (2000 2550)(2425 2550);
WIRE 16 -1 (2000 2600)(2425 2600);
WIRE 16 -1 (2000 2650)(2425 2650);
WIRE 16 -1 (2000 2700)(2425 2700);
WIRE 16 -1 (2000 2750)(2425 2750);
WIRE 16 -1 (2000 2800)(2425 2800);
WIRE 16 -1 (2000 750)(2425 750);
WIRE 16 -1 (2000 800)(2425 800);
WIRE 16 -1 (2000 850)(2425 850);
WIRE 16 -1 (2000 900)(2425 900);
WIRE 16 -1 (2000 1400)(2425 1400);
WIRE 16 -1 (2000 1450)(2425 1450);
WIRE 16 -1 (2000 1500)(2425 1500);
WIRE 16 -1 (2000 1550)(2425 1550);
WIRE 16 -1 (2000 1600)(2425 1600);
WIRE 16 -1 (2000 1650)(2425 1650);
WIRE 16 -1 (2000 1700)(2425 1700);
WIRE 16 -1 (3525 1850)(2000 1850);
FORCEPROP 2 LAST SIG_NAME M_H_CPU0_SA_PAR
J 0
(2634 1859);
DISPLAY 0.680851 (2634 1859);
PAINT WHITE (2634 1859);
WIRE 16 -1 (2000 4050)(2425 4050);
WIRE 16 -1 (2000 4100)(2425 4100);
WIRE 16 -1 (2000 4150)(2425 4150);
WIRE 16 -1 (2000 4200)(2425 4200);
WIRE 16 -1 (2000 4250)(2425 4250);
WIRE 16 -1 (2000 4300)(2425 4300);
WIRE 16 -1 (2000 4350)(2425 4350);
WIRE 16 -1 (2000 4400)(2425 4400);
WIRE 16 -1 (2000 4450)(2425 4450);
WIRE 16 -1 (2000 4500)(2425 4500);
WIRE 16 -1 (2000 3500)(2425 3500);
WIRE 16 -1 (2000 3550)(2425 3550);
WIRE 16 -1 (2000 3600)(2425 3600);
WIRE 16 -1 (2000 3650)(2425 3650);
WIRE 16 -1 (2000 3700)(2425 3700);
WIRE 16 -1 (2000 3750)(2425 3750);
WIRE 16 -1 (2000 3800)(2425 3800);
WIRE 16 -1 (2000 3850)(2425 3850);
WIRE 16 -1 (2000 3900)(2425 3900);
WIRE 16 -1 (2000 3950)(2425 3950);
WIRE 16 -1 (2000 1050)(2425 1050);
WIRE 16 -1 (2000 1100)(2425 1100);
WIRE 16 -1 (2000 1150)(2425 1150);
WIRE 16 -1 (2000 1200)(2425 1200);
WIRE 16 -1 (2000 1900)(2425 1900);
WIRE 16 -1 (2000 1950)(2425 1950);
WIRE 16 -1 (2000 2000)(2425 2000);
WIRE 16 -1 (2000 2050)(2425 2050);
WIRE 16 -1 (2000 2100)(2425 2100);
WIRE 16 -1 (2000 2150)(2425 2150);
WIRE 16 -1 (2000 2200)(2425 2200);
WIRE 16 -1 (3525 400)(2000 400);
FORCEPROP 2 LAST SIG_NAME M_H_CPU0_SB_RSP<0>
J 0
(2634 409);
DISPLAY 0.680851 (2634 409);
PAINT WHITE (2634 409);
WIRE 16 -1 (3525 450)(2000 450);
FORCEPROP 2 LAST SIG_NAME M_H_CPU0_SB_RSP<1>
J 0
(2634 459);
DISPLAY 0.680851 (2634 459);
PAINT WHITE (2634 459);
WIRE 16 -1 (3525 550)(2000 550);
FORCEPROP 2 LAST SIG_NAME M_H_CPU0_SA_RSP<0>
J 0
(2634 559);
DISPLAY 0.680851 (2634 559);
PAINT WHITE (2634 559);
WIRE 16 -1 (3525 600)(2000 600);
FORCEPROP 2 LAST SIG_NAME M_H_CPU0_SA_RSP<1>
J 0
(2634 609);
DISPLAY 0.680851 (2634 609);
PAINT WHITE (2634 609);
WIRE 16 -1 (3525 300)(2000 300);
FORCEPROP 2 LAST SIG_NAME M_H_CPU0_ALERT_N
J 0
(2634 309);
DISPLAY 0.680851 (2634 309);
PAINT WHITE (2634 309);
QUIT
